%FSTAX23Y23*%
%MOIN*%
%SFA1B1*%

%IPPOS*%
%ADD143C,0.120000*%
%ADD158C,0.061020*%
%ADD160C,0.075000*%
%ADD161C,0.098430*%
%ADD162O,0.088580X0.177170*%
%ADD163O,0.177170X0.088580*%
%ADD171C,0.016000*%
%ADD172C,0.200000*%
%LNgrandmaster-1*%
%LPD*%
G36*
X07082Y04353D02*
Y00505D01*
X03109*
Y00225*
X02289*
Y0031*
X02257Y00342*
X02229*
X02197Y0031*
Y00225*
X01776*
Y00352*
X01781Y00353*
X01782Y00352*
X01782Y00348*
X01786Y00343*
X01791Y00339*
X01797Y00338*
X01804Y00339*
X01809Y00343*
X01812Y00348*
X01814Y00355*
X01812Y00361*
X01809Y00366*
X01804Y0037*
X01797Y00371*
X01791Y0037*
X01786Y00366*
X01782Y00361*
X01782Y00357*
X01781Y00357*
X01776Y00357*
Y00465*
X0173Y00511*
X01658*
X01613Y00466*
Y00312*
X01316*
Y00508*
X00576*
Y00184*
X00002*
Y04349*
X00006Y04353*
X07082*
G37*
%LNgrandmaster-2*%
%LPC*%
G36*
X0257Y04299D02*
X02564Y04298D01*
X02559Y04294*
X02555Y04289*
X02554Y04283*
X02555Y04276*
X02559Y04271*
X02564Y04267*
X0257Y04266*
X02577Y04267*
X02582Y04271*
X02585Y04276*
X02587Y04283*
X02585Y04289*
X02582Y04294*
X02577Y04298*
X0257Y04299*
G37*
G36*
X01294Y04272D02*
X01288Y04271D01*
X01283Y04267*
X01279Y04262*
X01278Y04256*
X01279Y04249*
X01283Y04244*
X01288Y0424*
X01294Y04239*
X01301Y0424*
X01306Y04244*
X01309Y04249*
X01311Y04256*
X01309Y04262*
X01306Y04267*
X01301Y04271*
X01294Y04272*
G37*
G36*
X02078Y04293D02*
X02007D01*
Y04222*
X02078*
Y04293*
G37*
G36*
X01493Y04289D02*
X01422D01*
Y04218*
X01493*
Y04289*
G37*
G36*
X01557Y04245D02*
X01551Y04244D01*
X01546Y0424*
X01542Y04235*
X01541Y04229*
X01542Y04222*
X01546Y04217*
X01551Y04213*
X01557Y04212*
X01564Y04213*
X01569Y04217*
X01572Y04222*
X01574Y04229*
X01572Y04235*
X01569Y0424*
X01564Y04244*
X01557Y04245*
G37*
G36*
X01345Y04191D02*
X01339Y0419D01*
X01333Y04186*
X0133Y04181*
X01329Y04175*
X0133Y04168*
X01333Y04163*
X01339Y0416*
X01345Y04158*
X01351Y0416*
X01357Y04163*
X0136Y04168*
X01361Y04175*
X0136Y04181*
X01357Y04186*
X01351Y0419*
X01345Y04191*
G37*
G36*
X01569Y04187D02*
X01563Y04186D01*
X01558Y04182*
X01554Y04177*
X01553Y04171*
X01554Y04165*
X01558Y04159*
X01563Y04156*
X01569Y04154*
X01576Y04156*
X01581Y04159*
X01584Y04165*
X01586Y04171*
X01584Y04177*
X01581Y04182*
X01576Y04186*
X01569Y04187*
G37*
G36*
X01779Y04172D02*
X01773Y04171D01*
X01768Y04167*
X01764Y04162*
X01763Y04156*
X01764Y04149*
X01768Y04144*
X01773Y0414*
X01779Y04139*
X01786Y0414*
X01791Y04144*
X01794Y04149*
X01796Y04156*
X01794Y04162*
X01791Y04167*
X01786Y04171*
X01779Y04172*
G37*
G36*
X02043Y04193D02*
X02034Y04192D01*
X02025Y04188*
X02017Y04183*
X02012Y04175*
X02008Y04167*
X02007Y04157*
X02008Y04148*
X02012Y04139*
X02017Y04132*
X02025Y04126*
X02034Y04123*
X02043Y04122*
X02052Y04123*
X02061Y04126*
X02068Y04132*
X02074Y04139*
X02077Y04148*
X02079Y04157*
X02077Y04167*
X02074Y04175*
X02068Y04183*
X02061Y04188*
X02052Y04192*
X02043Y04193*
G37*
G36*
X01457Y04189D02*
X01448Y04188D01*
X01439Y04184*
X01432Y04179*
X01426Y04171*
X01423Y04163*
X01421Y04153*
X01423Y04144*
X01426Y04136*
X01432Y04128*
X01439Y04122*
X01448Y04119*
X01457Y04118*
X01466Y04119*
X01475Y04122*
X01483Y04128*
X01488Y04136*
X01492Y04144*
X01493Y04153*
X01492Y04163*
X01488Y04171*
X01483Y04179*
X01475Y04184*
X01466Y04188*
X01457Y04189*
G37*
G36*
X03958Y04152D02*
X03951Y04151D01*
X03945Y04148*
X03939Y04144*
X03935Y04139*
X03933Y04132*
X03932Y04126*
X03933Y04119*
X03935Y04113*
X03939Y04107*
X03945Y04103*
X03951Y04101*
X03958Y041*
X03964Y04101*
X03971Y04103*
X03976Y04107*
X0398Y04113*
X03983Y04119*
X03984Y04126*
X03983Y04132*
X0398Y04139*
X03976Y04144*
X03971Y04148*
X03964Y04151*
X03958Y04152*
G37*
G36*
X03784D02*
X03778Y04151D01*
X03771Y04148*
X03766Y04144*
X03762Y04139*
X03759Y04132*
X03758Y04126*
X03759Y04119*
X03762Y04113*
X03766Y04107*
X03771Y04103*
X03778Y04101*
X03784Y041*
X03791Y04101*
X03797Y04103*
X03803Y04107*
X03807Y04113*
X03809Y04119*
X0381Y04126*
X03809Y04132*
X03807Y04139*
X03803Y04144*
X03797Y04148*
X03791Y04151*
X03784Y04152*
G37*
G36*
X04754Y04132D02*
X04748Y04131D01*
X04743Y04127*
X04739Y04122*
X04738Y04115*
X04739Y04109*
X04743Y04104*
X04748Y041*
X04754Y04099*
X0476Y041*
X04766Y04104*
X04769Y04109*
X04771Y04115*
X04769Y04122*
X04766Y04127*
X0476Y04131*
X04754Y04132*
G37*
G36*
X02146Y0412D02*
X02139Y04118D01*
X02134Y04115*
X02131Y0411*
X02129Y04103*
X02131Y04097*
X02134Y04092*
X02139Y04088*
X02146Y04087*
X02152Y04088*
X02157Y04092*
X02161Y04097*
X02162Y04103*
X02161Y0411*
X02157Y04115*
X02152Y04118*
X02146Y0412*
G37*
G36*
X05267Y04105D02*
X0526Y04103D01*
X05255Y041*
X05251Y04095*
X0525Y04088*
X05251Y04082*
X05255Y04077*
X0526Y04073*
X05267Y04072*
X05273Y04073*
X05278Y04077*
X05282Y04082*
X05283Y04088*
X05282Y04095*
X05278Y041*
X05273Y04103*
X05267Y04105*
G37*
G36*
X02253Y04102D02*
X02247Y04101D01*
X02242Y04098*
X02238Y04092*
X02237Y04086*
X02238Y0408*
X02242Y04075*
X02247Y04071*
X02253Y0407*
X0226Y04071*
X02265Y04075*
X02269Y0408*
X0227Y04086*
X02269Y04092*
X02265Y04098*
X0226Y04101*
X02253Y04102*
G37*
G36*
X03504Y04102D02*
X03498Y04101D01*
X03493Y04097*
X03489Y04092*
X03488Y04086*
X03489Y04079*
X03493Y04074*
X03498Y0407*
X03504Y04069*
X03511Y0407*
X03516Y04074*
X03519Y04079*
X03521Y04086*
X03519Y04092*
X03516Y04097*
X03511Y04101*
X03504Y04102*
G37*
G36*
X03294Y04127D02*
X03284Y04126D01*
X03274Y04121*
X03265Y04115*
X03259Y04106*
X03254Y04096*
X03253Y04086*
X03254Y04075*
X03259Y04065*
X03265Y04056*
X03274Y0405*
X03284Y04046*
X03294Y04044*
X03305Y04046*
X03315Y0405*
X03324Y04056*
X0333Y04065*
X03334Y04075*
X03336Y04086*
X03334Y04096*
X0333Y04106*
X03324Y04115*
X03315Y04121*
X03305Y04126*
X03294Y04127*
G37*
G36*
X02994D02*
X02984Y04126D01*
X02974Y04121*
X02965Y04115*
X02959Y04106*
X02954Y04096*
X02953Y04086*
X02954Y04075*
X02959Y04065*
X02965Y04056*
X02974Y0405*
X02984Y04046*
X02994Y04044*
X03005Y04046*
X03015Y0405*
X03024Y04056*
X0303Y04065*
X03034Y04075*
X03036Y04086*
X03034Y04096*
X0303Y04106*
X03024Y04115*
X03015Y04121*
X03005Y04126*
X02994Y04127*
G37*
G36*
X069Y0416D02*
X06887Y04159D01*
X06874Y04155*
X06862Y04149*
X06852Y04141*
X06844Y0413*
X06837Y04119*
X06834Y04106*
X06832Y04093*
X06834Y0408*
X06837Y04067*
X06844Y04056*
X06852Y04045*
X06862Y04037*
X06874Y04031*
X06887Y04027*
X069Y04026*
X06913Y04027*
X06925Y04031*
X06937Y04037*
X06947Y04045*
X06956Y04056*
X06962Y04067*
X06966Y0408*
X06967Y04093*
X06966Y04106*
X06962Y04119*
X06956Y0413*
X06947Y04141*
X06937Y04149*
X06925Y04155*
X06913Y04159*
X069Y0416*
G37*
G36*
X06569D02*
X06556Y04159D01*
X06543Y04155*
X06532Y04149*
X06521Y04141*
X06513Y0413*
X06507Y04119*
X06503Y04106*
X06502Y04093*
X06503Y0408*
X06507Y04067*
X06513Y04056*
X06521Y04045*
X06532Y04037*
X06543Y04031*
X06556Y04027*
X06569Y04026*
X06582Y04027*
X06595Y04031*
X06606Y04037*
X06617Y04045*
X06625Y04056*
X06631Y04067*
X06635Y0408*
X06636Y04093*
X06635Y04106*
X06631Y04119*
X06625Y0413*
X06617Y04141*
X06606Y04149*
X06595Y04155*
X06582Y04159*
X06569Y0416*
G37*
G36*
X02043Y04093D02*
X02034Y04092D01*
X02025Y04088*
X02017Y04083*
X02012Y04075*
X02008Y04067*
X02007Y04057*
X02008Y04048*
X02012Y04039*
X02017Y04032*
X02025Y04026*
X02034Y04023*
X02043Y04022*
X02052Y04023*
X02061Y04026*
X02068Y04032*
X02074Y04039*
X02077Y04048*
X02079Y04057*
X02077Y04067*
X02074Y04075*
X02068Y04083*
X02061Y04088*
X02052Y04092*
X02043Y04093*
G37*
G36*
X00285Y04285D02*
X00264Y04283D01*
X00244Y04278*
X00224Y0427*
X00207Y04259*
X00191Y04246*
X00177Y0423*
X00166Y04212*
X00158Y04193*
X00153Y04172*
X00152Y04152*
X00153Y04131*
X00158Y0411*
X00166Y04091*
X00177Y04073*
X00191Y04057*
X00207Y04044*
X00224Y04033*
X00244Y04025*
X00264Y0402*
X00285Y04018*
X00306Y0402*
X00326Y04025*
X00346Y04033*
X00363Y04044*
X00379Y04057*
X00393Y04073*
X00404Y04091*
X00412Y0411*
X00417Y04131*
X00418Y04152*
X00417Y04172*
X00412Y04193*
X00404Y04212*
X00393Y0423*
X00379Y04246*
X00363Y04259*
X00346Y0427*
X00326Y04278*
X00306Y04283*
X00285Y04285*
G37*
G36*
X01457Y04089D02*
X01448Y04088D01*
X01439Y04084*
X01432Y04079*
X01426Y04071*
X01423Y04063*
X01421Y04053*
X01423Y04044*
X01426Y04036*
X01432Y04028*
X01439Y04022*
X01448Y04019*
X01457Y04018*
X01466Y04019*
X01475Y04022*
X01483Y04028*
X01488Y04036*
X01492Y04044*
X01493Y04053*
X01492Y04063*
X01488Y04071*
X01483Y04079*
X01475Y04084*
X01466Y04088*
X01457Y04089*
G37*
G36*
X01903Y04034D02*
X01897Y04033D01*
X01892Y04029*
X01888Y04024*
X01887Y04018*
X01888Y04011*
X01892Y04006*
X01897Y04002*
X01903Y04001*
X0191Y04002*
X01915Y04006*
X01918Y04011*
X0192Y04018*
X01918Y04024*
X01915Y04029*
X0191Y04033*
X01903Y04034*
G37*
G36*
X02353Y04034D02*
X02347Y04032D01*
X02341Y04029*
X02338Y04023*
X02337Y04017*
X02338Y04011*
X02341Y04006*
X02347Y04002*
X02353Y04001*
X02359Y04002*
X02364Y04006*
X02368Y04011*
X02369Y04017*
X02368Y04023*
X02364Y04029*
X02359Y04032*
X02353Y04034*
G37*
G36*
X05723Y04083D02*
X05708Y04081D01*
X05694Y04075*
X05682Y04066*
X05673Y04054*
X05667Y0404*
X05665Y04025*
X05667Y0401*
X05673Y03996*
X05682Y03984*
X05694Y03975*
X05708Y03969*
X05723Y03967*
X05738Y03969*
X05752Y03975*
X05764Y03984*
X05773Y03996*
X05779Y0401*
X05781Y04025*
X05779Y0404*
X05773Y04054*
X05764Y04066*
X05752Y04075*
X05738Y04081*
X05723Y04083*
G37*
G36*
X01408Y03996D02*
X01402Y03995D01*
X01396Y03991*
X01393Y03986*
X01392Y0398*
X01393Y03974*
X01396Y03968*
X01402Y03965*
X01408Y03964*
X01414Y03965*
X0142Y03968*
X01423Y03974*
X01424Y0398*
X01423Y03986*
X0142Y03991*
X01414Y03995*
X01408Y03996*
G37*
G36*
X02084Y03912D02*
X02078Y03911D01*
X02073Y03907*
X02069Y03902*
X02068Y03896*
X02069Y03889*
X02069Y03889*
X02066Y03885*
X02066Y03886*
X02059Y03887*
X02053Y03886*
X02048Y03882*
X02044Y03877*
X02043Y03871*
X02044Y03864*
X02048Y03859*
X02053Y03855*
X02059Y03854*
X02066Y03855*
X02071Y03859*
X02074Y03864*
X02076Y03871*
X02074Y03877*
X02074Y03877*
X02078Y03881*
X02078Y0388*
X02084Y03879*
X02091Y0388*
X02096Y03884*
X02099Y03889*
X02101Y03896*
X02099Y03902*
X02096Y03907*
X02091Y03911*
X02084Y03912*
G37*
G36*
X02029Y03852D02*
X02023Y03851D01*
X02018Y03847*
X02014Y03842*
X02013Y03836*
X02013Y03835*
X02013Y03834*
X02009Y03831*
X02004Y03832*
X01998Y03831*
X01993Y03827*
X01989Y03822*
X01988Y03816*
X01989Y03809*
X01993Y03804*
X01998Y038*
X02004Y03799*
X02011Y038*
X02016Y03804*
X02019Y03809*
X02021Y03816*
X02021Y03816*
X02021Y03817*
X02025Y0382*
X02029Y03819*
X02036Y0382*
X02041Y03824*
X02044Y03829*
X02046Y03836*
X02044Y03842*
X02041Y03847*
X02036Y03851*
X02029Y03852*
G37*
G36*
X03699D02*
X03693Y03851D01*
X03688Y03847*
X03684Y03842*
X03683Y03836*
X03684Y03829*
X03688Y03824*
X03693Y0382*
X03699Y03819*
X03706Y0382*
X03711Y03824*
X03714Y03829*
X03716Y03836*
X03714Y03842*
X03711Y03847*
X03706Y03851*
X03699Y03852*
G37*
G36*
X03014Y03847D02*
X03008Y03846D01*
X03003Y03842*
X02999Y03837*
X02998Y03831*
X02999Y03824*
X03003Y03819*
X03008Y03815*
X03014Y03814*
X03021Y03815*
X03026Y03819*
X03029Y03824*
X03031Y03831*
X03029Y03837*
X03026Y03842*
X03021Y03846*
X03014Y03847*
G37*
G36*
X03829Y03822D02*
X03823Y03821D01*
X03818Y03817*
X03814Y03812*
X03813Y03806*
X03814Y03799*
X03818Y03794*
X03823Y0379*
X03829Y03789*
X03836Y0379*
X03841Y03794*
X03844Y03799*
X03846Y03806*
X03844Y03812*
X03841Y03817*
X03836Y03821*
X03829Y03822*
G37*
G36*
X03539D02*
X03533Y03821D01*
X03528Y03817*
X03524Y03812*
X03523Y03806*
X03524Y03799*
X03528Y03794*
X03533Y0379*
X03539Y03789*
X03546Y0379*
X03551Y03794*
X03554Y03799*
X03556Y03806*
X03554Y03812*
X03551Y03817*
X03546Y03821*
X03539Y03822*
G37*
G36*
X03219D02*
X03213Y03821D01*
X03208Y03817*
X03204Y03812*
X03203Y03806*
X03204Y03799*
X03208Y03794*
X03213Y0379*
X03219Y03789*
X03226Y0379*
X03231Y03794*
X03234Y03799*
X03236Y03806*
X03234Y03812*
X03231Y03817*
X03226Y03821*
X03219Y03822*
G37*
G36*
X05723Y03902D02*
X05708Y039D01*
X05694Y03894*
X05682Y03885*
X05673Y03873*
X05667Y03859*
X05665Y03844*
X05667Y03829*
X05673Y03815*
X05682Y03803*
X05694Y03794*
X05708Y03788*
X05723Y03786*
X05738Y03788*
X05752Y03794*
X05764Y03803*
X05773Y03815*
X05779Y03829*
X05781Y03844*
X05779Y03859*
X05773Y03873*
X05764Y03885*
X05752Y03894*
X05738Y039*
X05723Y03902*
G37*
G36*
X02722Y03802D02*
X02716Y03801D01*
X0271Y03797*
X02707Y03792*
X02706Y03786*
X02707Y03779*
X0271Y03774*
X02716Y03771*
X02722Y03769*
X02728Y03771*
X02733Y03774*
X02737Y03779*
X02738Y03786*
X02737Y03792*
X02733Y03797*
X02728Y03801*
X02722Y03802*
G37*
G36*
X06169Y03877D02*
X0607D01*
X06055Y03875*
X06041Y03869*
X06029Y0386*
X0602Y03848*
X06014Y03834*
X06012Y03819*
X06014Y03804*
X0602Y0379*
X06029Y03779*
X06041Y03769*
X06055Y03764*
X0607Y03762*
X06169*
X06183Y03764*
X06197Y03769*
X06209Y03779*
X06219Y0379*
X06224Y03804*
X06226Y03819*
X06224Y03834*
X06219Y03848*
X06209Y0386*
X06197Y03869*
X06183Y03875*
X06169Y03877*
G37*
G36*
X04254Y03792D02*
X04248Y03791D01*
X04243Y03787*
X04239Y03782*
X04238Y03776*
X04239Y03769*
X04243Y03764*
X04248Y0376*
X04254Y03759*
X04261Y0376*
X04266Y03764*
X04269Y03769*
X04271Y03776*
X04269Y03782*
X04266Y03787*
X04261Y03791*
X04254Y03792*
G37*
G36*
X069Y03863D02*
X06885Y03861D01*
X06871Y03856*
X06859Y03846*
X0685Y03834*
X06844Y03821*
X06842Y03806*
X06844Y03791*
X0685Y03777*
X06859Y03765*
X06871Y03756*
X06885Y0375*
X069Y03748*
X06915Y0375*
X06929Y03756*
X06941Y03765*
X0695Y03777*
X06955Y03791*
X06957Y03806*
X06955Y03821*
X0695Y03834*
X06941Y03846*
X06929Y03856*
X06915Y03861*
X069Y03863*
G37*
G36*
X06734D02*
X06719Y03861D01*
X06705Y03856*
X06694Y03846*
X06684Y03834*
X06679Y03821*
X06677Y03806*
X06679Y03791*
X06684Y03777*
X06694Y03765*
X06705Y03756*
X06719Y0375*
X06734Y03748*
X06749Y0375*
X06763Y03756*
X06775Y03765*
X06784Y03777*
X0679Y03791*
X06792Y03806*
X0679Y03821*
X06784Y03834*
X06775Y03846*
X06763Y03856*
X06749Y03861*
X06734Y03863*
G37*
G36*
X06569D02*
X06554Y03861D01*
X0654Y03856*
X06528Y03846*
X06519Y03834*
X06513Y03821*
X06511Y03806*
X06513Y03791*
X06519Y03777*
X06528Y03765*
X0654Y03756*
X06554Y0375*
X06569Y03748*
X06584Y0375*
X06598Y03756*
X0661Y03765*
X06619Y03777*
X06625Y03791*
X06627Y03806*
X06625Y03821*
X06619Y03834*
X0661Y03846*
X06598Y03856*
X06584Y03861*
X06569Y03863*
G37*
G36*
X03699Y03767D02*
X03693Y03766D01*
X03688Y03762*
X03684Y03757*
X03683Y03751*
X03684Y03744*
X03688Y03739*
X03693Y03735*
X03699Y03734*
X03706Y03735*
X03711Y03739*
X03714Y03744*
X03716Y03751*
X03714Y03757*
X03711Y03762*
X03706Y03766*
X03699Y03767*
G37*
G36*
X02993D02*
X02987Y03766D01*
X02981Y03762*
X02978Y03757*
X02977Y03751*
X02978Y03744*
X02981Y03739*
X02987Y03735*
X02993Y03734*
X02999Y03735*
X03004Y03739*
X03008Y03744*
X03009Y03751*
X03008Y03757*
X03004Y03762*
X02999Y03766*
X02993Y03767*
G37*
G36*
X06294Y03717D02*
X06288Y03716D01*
X06283Y03712*
X06279Y03707*
X06278Y03701*
X06279Y03694*
X06283Y03689*
X06288Y03685*
X06294Y03684*
X06301Y03685*
X06306Y03689*
X06309Y03694*
X06311Y03701*
X06309Y03707*
X06306Y03712*
X06301Y03716*
X06294Y03717*
G37*
G36*
X01849D02*
X01843Y03716D01*
X01838Y03712*
X01834Y03707*
X01833Y03701*
X01834Y03694*
X01838Y03689*
X01843Y03685*
X01849Y03684*
X01856Y03685*
X01861Y03689*
X01864Y03694*
X01866Y03701*
X01864Y03707*
X01861Y03712*
X01856Y03716*
X01849Y03717*
G37*
G36*
X04049Y03681D02*
X04043Y0368D01*
X04038Y03676*
X04034Y03671*
X04033Y03665*
X04034Y03658*
X04038Y03653*
X04043Y03649*
X04049Y03648*
X04056Y03649*
X04061Y03653*
X04064Y03658*
X04066Y03665*
X04064Y03671*
X04061Y03676*
X04056Y0368*
X04049Y03681*
G37*
G36*
X02679Y03677D02*
X02673Y03676D01*
X02668Y03672*
X02664Y03667*
X02663Y03661*
X02664Y03654*
X02668Y03649*
X02673Y03645*
X02679Y03644*
X02686Y03645*
X02691Y03649*
X02694Y03654*
X02696Y03661*
X02694Y03667*
X02691Y03672*
X02686Y03676*
X02679Y03677*
G37*
G36*
X01754D02*
X01748Y03676D01*
X01743Y03672*
X01739Y03667*
X01738Y03661*
X01739Y03654*
X01743Y03649*
X01748Y03645*
X01754Y03644*
X01761Y03645*
X01766Y03649*
X01769Y03654*
X01771Y03661*
X01769Y03667*
X01766Y03672*
X01761Y03676*
X01754Y03677*
G37*
G36*
X03424Y03652D02*
X03418Y03651D01*
X03413Y03647*
X03409Y03642*
X03408Y03636*
X03409Y03629*
X03413Y03624*
X03418Y0362*
X03424Y03619*
X03431Y0362*
X03436Y03624*
X03439Y03629*
X03441Y03636*
X03439Y03642*
X03436Y03647*
X03431Y03651*
X03424Y03652*
G37*
G36*
X02799Y03632D02*
X02793Y03631D01*
X02788Y03627*
X02784Y03622*
X02783Y03616*
X02784Y03609*
X02788Y03604*
X02793Y036*
X02799Y03599*
X02806Y036*
X02811Y03604*
X02814Y03609*
X02816Y03616*
X02814Y03622*
X02811Y03627*
X02806Y03631*
X02799Y03632*
G37*
G36*
X02139Y03627D02*
X02133Y03626D01*
X02128Y03622*
X02124Y03617*
X02123Y03611*
X02124Y03604*
X02128Y03599*
X02133Y03595*
X02139Y03594*
X02146Y03595*
X02151Y03599*
X02154Y03604*
X02156Y03611*
X02154Y03617*
X02151Y03622*
X02146Y03626*
X02139Y03627*
G37*
G36*
X01884Y03617D02*
X01878Y03616D01*
X01873Y03612*
X01869Y03607*
X01868Y03601*
X01869Y03594*
X01873Y03589*
X01878Y03585*
X01884Y03584*
X01891Y03585*
X01896Y03589*
X01899Y03594*
X01901Y03601*
X01899Y03607*
X01896Y03612*
X01891Y03616*
X01884Y03617*
G37*
G36*
X03239Y03612D02*
X03233Y03611D01*
X03228Y03607*
X03224Y03602*
X03223Y03596*
X03224Y03589*
X03228Y03584*
X03233Y0358*
X03239Y03579*
X03246Y0358*
X03251Y03584*
X03254Y03589*
X03256Y03596*
X03254Y03602*
X03251Y03607*
X03246Y03611*
X03239Y03612*
G37*
G36*
X01549Y03637D02*
X01543Y03636D01*
X01538Y03632*
X01534Y03627*
X01533Y03621*
X01534Y03614*
X01538Y03609*
X01543Y03605*
X01549Y03604*
X01556Y03605*
X01556Y03606*
X01559Y03602*
X01559Y03602*
X01558Y03596*
X01559Y03589*
X01563Y03584*
X01568Y0358*
X01574Y03579*
X01581Y0358*
X01586Y03584*
X01589Y03589*
X01591Y03596*
X01589Y03602*
X01586Y03607*
X01581Y03611*
X01574Y03612*
X01568Y03611*
X01568Y0361*
X01564Y03614*
X01564Y03614*
X01566Y03621*
X01564Y03627*
X01561Y03632*
X01556Y03636*
X01549Y03637*
G37*
G36*
X02422Y03624D02*
X02413Y03623D01*
X02405Y03617*
X024Y0361*
X02398Y03601*
X024Y03592*
X02405Y03584*
X02413Y03579*
X02422Y03577*
X02431Y03579*
X02438Y03584*
X02443Y03592*
X02445Y03601*
X02443Y0361*
X02438Y03617*
X02431Y03623*
X02422Y03624*
G37*
G36*
X02774Y03582D02*
X02768Y03581D01*
X02763Y03577*
X02759Y03572*
X02758Y03566*
X02759Y03559*
X02763Y03554*
X02768Y0355*
X02774Y03549*
X02781Y0355*
X02786Y03554*
X02789Y03559*
X02791Y03566*
X02789Y03572*
X02786Y03577*
X02781Y03581*
X02774Y03582*
G37*
G36*
X0144Y03573D02*
X01434Y03572D01*
X01429Y03568*
X01425Y03563*
X01424Y03557*
X01425Y0355*
X01429Y03545*
X01434Y03541*
X0144Y0354*
X01447Y03541*
X01452Y03545*
X01455Y0355*
X01457Y03557*
X01455Y03563*
X01452Y03568*
X01447Y03572*
X0144Y03573*
G37*
G36*
X05994Y03568D02*
X05988Y03567D01*
X05983Y03563*
X05979Y03558*
X05978Y03552*
X05979Y03545*
X05983Y0354*
X05988Y03536*
X05994Y03535*
X06001Y03536*
X06006Y0354*
X06009Y03545*
X06011Y03552*
X06009Y03558*
X06006Y03563*
X06001Y03567*
X05994Y03568*
G37*
G36*
X02434Y03562D02*
X02428Y03561D01*
X02423Y03557*
X02419Y03552*
X02418Y03546*
X02419Y03539*
X02423Y03534*
X02428Y0353*
X02434Y03529*
X02441Y0353*
X02446Y03534*
X02449Y03539*
X02451Y03546*
X02449Y03552*
X02446Y03557*
X02441Y03561*
X02434Y03562*
G37*
G36*
X02254Y03552D02*
X02248Y03551D01*
X02243Y03547*
X02239Y03542*
X02238Y03536*
X02239Y03529*
X02242Y03525*
X02239Y03521*
X02234Y03522*
X02228Y03521*
X02223Y03517*
X02219Y03512*
X02218Y03506*
X02219Y03499*
X02223Y03494*
X02228Y0349*
X02234Y03489*
X02241Y0349*
X02246Y03494*
X02249Y03499*
X02251Y03506*
X02249Y03512*
X02247Y03516*
X0225Y0352*
X02254Y03519*
X02261Y0352*
X02266Y03524*
X02269Y03529*
X02271Y03536*
X02269Y03542*
X02266Y03547*
X02261Y03551*
X02254Y03552*
G37*
G36*
X05274Y03527D02*
X05268Y03526D01*
X05263Y03522*
X05259Y03517*
X05258Y03511*
X05259Y03504*
X05263Y03499*
X05268Y03495*
X05274Y03494*
X05281Y03495*
X05286Y03499*
X05289Y03504*
X05291Y03511*
X05289Y03517*
X05286Y03522*
X05281Y03526*
X05274Y03527*
G37*
G36*
X03622Y03502D02*
X03616Y03501D01*
X03611Y03497*
X03607Y03492*
X03606Y03486*
X03607Y03479*
X03611Y03474*
X03616Y0347*
X03622Y03469*
X03629Y0347*
X03634Y03474*
X03637Y03479*
X03639Y03486*
X03637Y03492*
X03634Y03497*
X03629Y03501*
X03622Y03502*
G37*
G36*
X02579D02*
X02573Y03501D01*
X02568Y03497*
X02564Y03492*
X02563Y03486*
X02564Y03479*
X02568Y03474*
X02573Y0347*
X02579Y03469*
X02586Y0347*
X02591Y03474*
X02594Y03479*
X02596Y03486*
X02594Y03492*
X02591Y03497*
X02586Y03501*
X02579Y03502*
G37*
G36*
X03529Y03497D02*
X03523Y03496D01*
X03518Y03492*
X03514Y03487*
X03513Y03481*
X03514Y03474*
X03518Y03469*
X03523Y03465*
X03529Y03464*
X03536Y03465*
X03541Y03469*
X03544Y03474*
X03546Y03481*
X03544Y03487*
X03541Y03492*
X03536Y03496*
X03529Y03497*
G37*
G36*
X02389D02*
X02383Y03496D01*
X02378Y03492*
X02374Y03487*
X02373Y03481*
X02374Y03474*
X02378Y03469*
X02383Y03465*
X02389Y03464*
X02396Y03465*
X02401Y03469*
X02404Y03474*
X02406Y03481*
X02404Y03487*
X02401Y03492*
X02396Y03496*
X02389Y03497*
G37*
G36*
X06509Y03472D02*
X06503Y03471D01*
X06498Y03467*
X06494Y03462*
X06493Y03456*
X06494Y03449*
X06498Y03444*
X06503Y0344*
X06509Y03439*
X06516Y0344*
X06521Y03444*
X06524Y03449*
X06526Y03456*
X06524Y03462*
X06521Y03467*
X06516Y03471*
X06509Y03472*
G37*
G36*
X03436Y03473D02*
X0343Y03472D01*
X03425Y03468*
X03421Y03463*
X0342Y03457*
X03421Y0345*
X03425Y03445*
X0343Y03441*
X03436Y0344*
X03443Y03441*
X03448Y03445*
X0345Y03448*
X0345Y03448*
X03456Y03447*
X03458Y03444*
X03463Y0344*
X03469Y03439*
X03476Y0344*
X03481Y03444*
X03484Y03449*
X03486Y03456*
X03484Y03462*
X03481Y03467*
X03476Y03471*
X03469Y03472*
X03463Y03471*
X03458Y03467*
X03456Y03464*
X03456Y03464*
X0345Y03465*
X03448Y03468*
X03443Y03472*
X03436Y03473*
G37*
G36*
X03358Y03464D02*
X03352Y03463D01*
X03347Y03459*
X03343Y03454*
X03342Y03448*
X03343Y03441*
X03347Y03436*
X03352Y03432*
X03358Y03431*
X03365Y03432*
X0337Y03436*
X03373Y03441*
X03374Y03443*
X03379*
X03379Y0344*
X03383Y03435*
X03388Y03431*
X03394Y0343*
X03401Y03431*
X03406Y03435*
X03409Y0344*
X03411Y03447*
X03409Y03453*
X03406Y03458*
X03401Y03462*
X03394Y03463*
X03388Y03462*
X03383Y03458*
X03379Y03453*
X03379Y03451*
X03374*
X03373Y03454*
X0337Y03459*
X03365Y03463*
X03358Y03464*
G37*
G36*
X02422Y03467D02*
X02413Y03465D01*
X02405Y0346*
X024Y03452*
X02398Y03443*
X024Y03434*
X02405Y03427*
X02413Y03422*
X02422Y0342*
X02431Y03422*
X02438Y03427*
X02443Y03434*
X02445Y03443*
X02443Y03452*
X02438Y0346*
X02431Y03465*
X02422Y03467*
G37*
G36*
X06479Y03442D02*
X06473Y03441D01*
X06468Y03437*
X06464Y03432*
X06463Y03426*
X06464Y03419*
X06468Y03414*
X06473Y0341*
X06479Y03409*
X06486Y0341*
X06491Y03414*
X06494Y03419*
X06496Y03426*
X06494Y03432*
X06491Y03437*
X06486Y03441*
X06479Y03442*
G37*
G36*
X02634Y03422D02*
X02628Y03421D01*
X02623Y03417*
X02619Y03412*
X02618Y03406*
X02619Y03399*
X02623Y03394*
X02628Y0339*
X02634Y03389*
X02641Y0339*
X02646Y03394*
X02649Y03399*
X02651Y03406*
X02649Y03412*
X02646Y03417*
X02641Y03421*
X02634Y03422*
G37*
G36*
X06447Y03412D02*
X06441Y03411D01*
X06436Y03407*
X06432Y03402*
X06431Y03396*
X06432Y03389*
X06436Y03384*
X06441Y0338*
X06447Y03379*
X06453Y0338*
X06459Y03384*
X06462Y03389*
X06463Y03396*
X06462Y03402*
X06459Y03407*
X06453Y03411*
X06447Y03412*
G37*
G36*
X03068Y03411D02*
X03062Y0341D01*
X03057Y03407*
X03053Y03401*
X03052Y03395*
X03053Y03389*
X03057Y03384*
X03062Y0338*
X03068Y03379*
X03075Y0338*
X0308Y03384*
X03083Y03389*
X03085Y03395*
X03083Y03401*
X0308Y03407*
X03075Y0341*
X03068Y03411*
G37*
G36*
X06409Y03387D02*
X06403Y03386D01*
X06398Y03382*
X06394Y03377*
X06393Y03371*
X06394Y03364*
X06398Y03359*
X06403Y03355*
X06409Y03354*
X06416Y03355*
X06421Y03359*
X06424Y03364*
X06426Y03371*
X06424Y03377*
X06421Y03382*
X06416Y03386*
X06409Y03387*
G37*
G36*
X03302Y0336D02*
X03296Y03359D01*
X03291Y03355*
X03287Y0335*
X03286Y03344*
X03287Y03337*
X03291Y03332*
X03296Y03328*
X03302Y03327*
X03309Y03328*
X03314Y03332*
X03317Y03337*
X03319Y03344*
X03317Y0335*
X03314Y03355*
X03309Y03359*
X03302Y0336*
G37*
G36*
X06354Y03347D02*
X06348Y03346D01*
X06343Y03342*
X06339Y03337*
X06338Y03331*
X06339Y03324*
X06343Y03319*
X06348Y03316*
X06354Y03314*
X0636Y03316*
X06366Y03319*
X06369Y03324*
X06371Y03331*
X06369Y03337*
X06366Y03342*
X0636Y03346*
X06354Y03347*
G37*
G36*
X03542Y03335D02*
X03536Y03334D01*
X03531Y0333*
X03527Y03325*
X03526Y03319*
X03527Y03312*
X03531Y03307*
X03536Y03303*
X03542Y03302*
X03549Y03303*
X03554Y03307*
X03557Y03312*
X03559Y03319*
X03557Y03325*
X03554Y0333*
X03549Y03334*
X03542Y03335*
G37*
G36*
X03263Y0332D02*
X03257Y03318D01*
X03252Y03315*
X03248Y0331*
X03247Y03303*
X03248Y03297*
X03252Y03292*
X03257Y03288*
X03263Y03287*
X03269Y03288*
X03275Y03292*
X03278Y03297*
X0328Y03303*
X03278Y0331*
X03275Y03315*
X03269Y03318*
X03263Y0332*
G37*
G36*
X03491Y03313D02*
X03485Y03312D01*
X0348Y03308*
X03476Y03303*
X03475Y03297*
X03476Y0329*
X0348Y03285*
X03485Y03281*
X03491Y0328*
X03498Y03281*
X03503Y03285*
X03506Y0329*
X03508Y03297*
X03506Y03303*
X03503Y03308*
X03498Y03312*
X03491Y03313*
G37*
G36*
X03653Y03309D02*
X03647Y03308D01*
X03642Y03304*
X03638Y03299*
X03637Y03293*
X03638Y03286*
X03642Y03281*
X03647Y03277*
X03653Y03276*
X0366Y03277*
X03665Y03281*
X03668Y03286*
X0367Y03293*
X03668Y03299*
X03665Y03304*
X0366Y03308*
X03653Y03309*
G37*
G36*
X06444Y03307D02*
X06438Y03306D01*
X06433Y03302*
X06429Y03297*
X06428Y03291*
X06429Y03284*
X06433Y03279*
X06438Y03275*
X06444Y03274*
X06451Y03275*
X06456Y03279*
X06459Y03284*
X06461Y03291*
X06459Y03297*
X06456Y03302*
X06451Y03306*
X06444Y03307*
G37*
G36*
X0259Y03304D02*
X02584Y03303D01*
X02579Y03299*
X02575Y03294*
X02574Y03288*
X02575Y03281*
X02579Y03276*
X02584Y03272*
X0259Y03271*
X02597Y03272*
X02602Y03276*
X02605Y03281*
X02607Y03288*
X02605Y03294*
X02602Y03299*
X02597Y03303*
X0259Y03304*
G37*
G36*
X03374Y03289D02*
X03368Y03288D01*
X03363Y03284*
X03359Y03279*
X03358Y03273*
X03359Y03266*
X03363Y03261*
X03368Y03257*
X03374Y03256*
X03381Y03257*
X03386Y03261*
X03389Y03266*
X03391Y03273*
X03389Y03279*
X03386Y03284*
X03381Y03288*
X03374Y03289*
G37*
G36*
X06334Y03282D02*
X06328Y03281D01*
X06323Y03277*
X06319Y03272*
X06318Y03266*
X06319Y03259*
X06323Y03254*
X06328Y0325*
X06334Y03249*
X06341Y0325*
X06346Y03254*
X06349Y03259*
X06351Y03266*
X06349Y03272*
X06346Y03277*
X06341Y03281*
X06334Y03282*
G37*
G36*
X03744Y03277D02*
X03738Y03276D01*
X03733Y03272*
X03729Y03267*
X03728Y03261*
X03729Y03254*
X03733Y03249*
X03738Y03245*
X03744Y03244*
X03751Y03245*
X03756Y03249*
X03759Y03254*
X03761Y03261*
X03759Y03267*
X03756Y03272*
X03751Y03276*
X03744Y03277*
G37*
G36*
X02259D02*
X02253Y03276D01*
X02248Y03272*
X02244Y03267*
X02243Y03261*
X02244Y03254*
X02248Y03249*
X02253Y03245*
X02259Y03244*
X02266Y03245*
X02271Y03249*
X02274Y03254*
X02276Y03261*
X02274Y03267*
X02271Y03272*
X02266Y03276*
X02259Y03277*
G37*
G36*
X0323Y03251D02*
X03224Y0325D01*
X03219Y03246*
X03215Y03241*
X03214Y03235*
X03215Y03228*
X03219Y03223*
X03224Y03219*
X0323Y03218*
X03237Y03219*
X03242Y03223*
X03245Y03228*
X03247Y03235*
X03245Y03241*
X03242Y03246*
X03237Y0325*
X0323Y03251*
G37*
G36*
X06282Y03242D02*
X06276Y03241D01*
X0627Y03237*
X06267Y03232*
X06266Y03226*
X06267Y03219*
X0627Y03214*
X06276Y0321*
X06282Y03209*
X06288Y0321*
X06293Y03214*
X06297Y03219*
X06298Y03226*
X06297Y03232*
X06293Y03237*
X06288Y03241*
X06282Y03242*
G37*
G36*
X03806Y03251D02*
X038Y0325D01*
X03795Y03246*
X03791Y03241*
X0379Y03235*
X03791Y03228*
X03795Y03223*
X03797Y03222*
X03796Y03216*
X03793Y03216*
X03788Y03212*
X03784Y03207*
X03783Y03201*
X03784Y03194*
X03788Y03189*
X03793Y03185*
X03799Y03184*
X03806Y03185*
X03811Y03189*
X03814Y03194*
X03816Y03201*
X03814Y03207*
X03811Y03212*
X03809Y03214*
X0381Y03219*
X03813Y03219*
X03818Y03223*
X03821Y03228*
X03823Y03235*
X03821Y03241*
X03818Y03246*
X03813Y0325*
X03806Y03251*
G37*
G36*
X02205Y03216D02*
X02199Y03215D01*
X02194Y03211*
X0219Y03206*
X02189Y032*
X0219Y03193*
X02194Y03188*
X02199Y03184*
X02205Y03183*
X02212Y03184*
X02217Y03188*
X0222Y03193*
X02222Y032*
X0222Y03206*
X02217Y03211*
X02212Y03215*
X02205Y03216*
G37*
G36*
X02422Y03263D02*
X02413Y03261D01*
X02405Y03256*
X024Y03248*
X02398Y03239*
X024Y0323*
X02405Y03223*
X02409Y0322*
X02408Y03215*
X02407Y03214*
X02402Y03211*
X02398Y03206*
X02397Y03199*
X02398Y03193*
X02402Y03188*
X02407Y03184*
X02414Y03183*
X0242Y03184*
X02425Y03188*
X02429Y03193*
X0243Y03199*
X02429Y03206*
X02425Y03211*
X02425Y03211*
X02426Y03217*
X02431Y03218*
X02438Y03223*
X02443Y0323*
X02445Y03239*
X02443Y03248*
X02438Y03256*
X02431Y03261*
X02422Y03263*
G37*
G36*
X06309Y03215D02*
X06303Y03214D01*
X06297Y0321*
X06294Y03205*
X06293Y03199*
X06294Y03192*
X06297Y03187*
X06303Y03183*
X06309Y03182*
X06315Y03183*
X0632Y03187*
X06324Y03192*
X06325Y03199*
X06324Y03205*
X0632Y0321*
X06315Y03214*
X06309Y03215*
G37*
G36*
X06439Y03207D02*
X06433Y03206D01*
X06428Y03202*
X06424Y03197*
X06423Y03191*
X06424Y03184*
X06428Y03179*
X06433Y03175*
X06439Y03174*
X06446Y03175*
X06451Y03179*
X06454Y03184*
X06456Y03191*
X06454Y03197*
X06451Y03202*
X06446Y03206*
X06439Y03207*
G37*
G36*
X03188Y03203D02*
X03182Y03202D01*
X03177Y03198*
X03173Y03193*
X03172Y03187*
X03173Y0318*
X03177Y03175*
X03182Y03171*
X03188Y0317*
X03195Y03171*
X032Y03175*
X03204Y0318*
X03205Y03187*
X03204Y03193*
X032Y03198*
X03195Y03202*
X03188Y03203*
G37*
G36*
X02591Y03202D02*
X02585Y03201D01*
X0258Y03197*
X02576Y03192*
X02575Y03186*
X02576Y03179*
X0258Y03174*
X02585Y03171*
X02591Y03169*
X02598Y03171*
X02603Y03174*
X02606Y03179*
X02608Y03186*
X02606Y03192*
X02603Y03197*
X02598Y03201*
X02591Y03202*
G37*
G36*
X02462Y03188D02*
X02456Y03187D01*
X0245Y03183*
X02447Y03178*
X02446Y03172*
X02447Y03166*
X0245Y0316*
X02456Y03157*
X02462Y03155*
X02468Y03157*
X02473Y0316*
X02477Y03166*
X02478Y03172*
X02477Y03178*
X02473Y03183*
X02468Y03187*
X02462Y03188*
G37*
G36*
X06339Y03167D02*
X06333Y03166D01*
X06328Y03162*
X06324Y03157*
X06323Y03151*
X06324Y03144*
X06328Y03139*
X06333Y03135*
X06339Y03134*
X06346Y03135*
X06351Y03139*
X06354Y03144*
X06356Y03151*
X06354Y03157*
X06351Y03162*
X06346Y03166*
X06339Y03167*
G37*
G36*
X03829Y03192D02*
X03823Y03191D01*
X03818Y03187*
X03814Y03182*
X03813Y03176*
X03814Y03169*
X03818Y03164*
X03823Y0316*
X03829Y03159*
X03836Y0316*
X03836Y03161*
X03839Y03157*
X03839Y03157*
X03838Y03151*
X03839Y03144*
X03843Y03139*
X03848Y03135*
X03854Y03134*
X03861Y03135*
X03866Y03139*
X03869Y03144*
X03871Y03151*
X03869Y03157*
X03866Y03162*
X03861Y03166*
X03854Y03167*
X03848Y03166*
X03848Y03165*
X03844Y03169*
X03844Y03169*
X03846Y03176*
X03844Y03182*
X03841Y03187*
X03836Y03191*
X03829Y03192*
G37*
G36*
X01459Y03163D02*
X01453Y03162D01*
X01448Y03158*
X01444Y03153*
X01443Y03147*
X01444Y0314*
X01448Y03135*
X01453Y03131*
X01459Y0313*
X01466Y03131*
X01471Y03135*
X01474Y0314*
X01476Y03147*
X01474Y03153*
X01471Y03158*
X01466Y03162*
X01459Y03163*
G37*
G36*
X03275Y03158D02*
X03269Y03156D01*
X03264Y03153*
X0326Y03147*
X03259Y03141*
X0326Y03135*
X03264Y0313*
X03269Y03126*
X03275Y03125*
X03281Y03126*
X03287Y0313*
X0329Y03135*
X03291Y03141*
X0329Y03147*
X03287Y03153*
X03281Y03156*
X03275Y03158*
G37*
G36*
X06304Y03137D02*
X06298Y03136D01*
X06293Y03132*
X06289Y03127*
X06288Y03121*
X06289Y03114*
X06293Y03109*
X06298Y03105*
X06304Y03104*
X06311Y03105*
X06316Y03109*
X06319Y03114*
X06321Y03121*
X06319Y03127*
X06316Y03132*
X06311Y03136*
X06304Y03137*
G37*
G36*
X03939D02*
X03933Y03136D01*
X03928Y03132*
X03924Y03127*
X03923Y03121*
X03924Y03114*
X03928Y03109*
X03933Y03105*
X03939Y03104*
X03946Y03105*
X03951Y03109*
X03954Y03114*
X03956Y03121*
X03954Y03127*
X03951Y03132*
X03946Y03136*
X03939Y03137*
G37*
G36*
X03491Y03119D02*
X03485Y03118D01*
X0348Y03114*
X03476Y03109*
X03475Y03103*
X03476Y03096*
X0348Y03091*
X03485Y03087*
X03491Y03086*
X03498Y03087*
X03503Y03091*
X03506Y03096*
X03508Y03103*
X03506Y03109*
X03503Y03114*
X03498Y03118*
X03491Y03119*
G37*
G36*
X02418Y03134D02*
X02412Y03133D01*
X02407Y0313*
X02403Y03124*
X02402Y03118*
X02403Y03112*
X02407Y03106*
X02408Y03106*
Y031*
X02405Y03098*
X024Y03091*
X02398Y03082*
X024Y03073*
X02405Y03065*
X02413Y0306*
X02422Y03058*
X02431Y0306*
X02438Y03065*
X02443Y03073*
X02445Y03082*
X02443Y03091*
X02438Y03098*
X02432Y03102*
X02431Y03105*
X02431Y03108*
X02433Y03112*
X02435Y03118*
X02433Y03124*
X0243Y0313*
X02424Y03133*
X02418Y03134*
G37*
G36*
X03368Y03066D02*
X03362Y03065D01*
X03357Y03061*
X03353Y03056*
X03352Y0305*
X03353Y03043*
X03357Y03038*
X03362Y03034*
X03368Y03033*
X03375Y03034*
X0338Y03038*
X03383Y03043*
X03385Y0305*
X03383Y03056*
X0338Y03061*
X03375Y03065*
X03368Y03066*
G37*
G36*
X03344Y03012D02*
X03338Y03011D01*
X03333Y03007*
X03329Y03002*
X03328Y02996*
X03329Y02989*
X03333Y02984*
X03338Y0298*
X03344Y02979*
X03351Y0298*
X03356Y02984*
X03359Y02989*
X03361Y02996*
X03359Y03002*
X03356Y03007*
X03351Y03011*
X03344Y03012*
G37*
G36*
X03197Y02986D02*
X03191Y02985D01*
X03186Y02981*
X03182Y02976*
X03181Y0297*
X03182Y02963*
X03186Y02958*
X03191Y02954*
X03197Y02953*
X03204Y02954*
X03209Y02958*
X03212Y02963*
X03214Y0297*
X03212Y02976*
X03209Y02981*
X03204Y02985*
X03197Y02986*
G37*
G36*
X04794Y02824D02*
X04788Y02823D01*
X04782Y02819*
X04779Y02814*
X04777Y02808*
X04779Y02801*
X04782Y02796*
X04788Y02793*
X04794Y02791*
X048Y02793*
X04805Y02796*
X04809Y02801*
X0481Y02808*
X04809Y02814*
X04805Y02819*
X048Y02823*
X04794Y02824*
G37*
G36*
X04503Y02806D02*
X04497Y02804D01*
X04492Y02801*
X04488Y02796*
X04487Y02789*
X04488Y02783*
X04492Y02778*
X04497Y02774*
X04503Y02773*
X04509Y02774*
X04515Y02778*
X04518Y02783*
X04519Y02789*
X04518Y02796*
X04515Y02801*
X04509Y02804*
X04503Y02806*
G37*
G36*
X02146Y02769D02*
X0214Y02768D01*
X02135Y02764*
X02131Y02759*
X0213Y02753*
X02131Y02746*
X02135Y02741*
X0214Y02737*
X02146Y02736*
X02153Y02737*
X02158Y02741*
X02161Y02746*
X02163Y02753*
X02161Y02759*
X02158Y02764*
X02153Y02768*
X02146Y02769*
G37*
G36*
X02692Y02737D02*
X02686Y02736D01*
X02681Y02732*
X02677Y02727*
X02676Y02721*
X02677Y02715*
X02681Y02709*
X02686Y02706*
X02692Y02705*
X02699Y02706*
X02704Y02709*
X02707Y02715*
X02709Y02721*
X02707Y02727*
X02704Y02732*
X02699Y02736*
X02692Y02737*
G37*
G36*
X02394Y02736D02*
X02388Y02735D01*
X02383Y02732*
X02379Y02726*
X02378Y0272*
X02379Y02714*
X02383Y02708*
X02388Y02705*
X02394Y02704*
X024Y02705*
X02406Y02708*
X02409Y02714*
X02411Y0272*
X02409Y02726*
X02406Y02732*
X024Y02735*
X02394Y02736*
G37*
G36*
X02494Y02712D02*
X02488Y02711D01*
X02483Y02707*
X02479Y02702*
X02478Y02696*
X02479Y02689*
X02483Y02684*
X02488Y02681*
X02488Y02679*
Y02678*
X02488Y02675*
X02483Y02672*
X02479Y02667*
X02478Y02661*
X02479Y02654*
X02483Y02649*
X02488Y02645*
X02494Y02644*
X02501Y02645*
X02506Y02649*
X02509Y02654*
X02511Y02661*
X02509Y02667*
X02506Y02672*
X02501Y02675*
X02501Y02678*
Y02679*
X02501Y02681*
X02506Y02684*
X02509Y02689*
X02511Y02696*
X02509Y02702*
X02506Y02707*
X02501Y02711*
X02494Y02712*
G37*
G36*
X02958Y02637D02*
X02952Y02636D01*
X02947Y02632*
X02943Y02627*
X02942Y02621*
X02943Y02614*
X02947Y02609*
X02952Y02605*
X02958Y02604*
X02965Y02605*
X0297Y02609*
X02973Y02614*
X02975Y02621*
X02973Y02627*
X0297Y02632*
X02965Y02636*
X02958Y02637*
G37*
G36*
X02429D02*
X02422Y02636D01*
X02417Y02632*
X02414Y02627*
X02412Y02621*
X02414Y02614*
X02417Y02609*
X02422Y02605*
X02429Y02604*
X02435Y02605*
X0244Y02609*
X02444Y02614*
X02445Y02621*
X02444Y02627*
X0244Y02632*
X02435Y02636*
X02429Y02637*
G37*
G36*
X02252Y02629D02*
X02246Y02628D01*
X0224Y02625*
X02237Y02619*
X02236Y02613*
X02237Y02607*
X02239Y02603*
X02236Y02599*
X02231Y026*
X02225Y02599*
X0222Y02595*
X02216Y0259*
X02215Y02584*
X02216Y02577*
X0222Y02572*
X02225Y02569*
X02231Y02567*
X02237Y02569*
X02243Y02572*
X02246Y02577*
X02248Y02584*
X02246Y0259*
X02244Y02594*
X02247Y02598*
X02252Y02597*
X02258Y02598*
X02263Y02602*
X02267Y02607*
X02268Y02613*
X02267Y02619*
X02263Y02625*
X02258Y02628*
X02252Y02629*
G37*
G36*
X02821Y02617D02*
X02815Y02616D01*
X0281Y02612*
X02806Y02607*
X02805Y02601*
X02806Y02594*
X0281Y02589*
X02815Y02585*
X02821Y02584*
X02828Y02585*
X02833Y02589*
X02836Y02594*
X02838Y02601*
X02836Y02607*
X02833Y02612*
X02828Y02616*
X02821Y02617*
G37*
G36*
X03623Y02603D02*
X03617Y02602D01*
X03612Y02598*
X03608Y02593*
X03607Y02587*
X03608Y0258*
X03612Y02575*
X03617Y02571*
X03623Y0257*
X0363Y02571*
X03635Y02575*
X03638Y0258*
X0364Y02587*
X03638Y02593*
X03635Y02598*
X0363Y02602*
X03623Y02603*
G37*
G36*
X04298Y02641D02*
X04286Y02639D01*
X04275Y02635*
X04266Y02627*
X04258Y02618*
X04254Y02607*
X04252Y02595*
X04254Y02583*
X04258Y02572*
X04266Y02562*
X04275Y02555*
X04286Y02551*
X04298Y02549*
X0431Y02551*
X04321Y02555*
X04331Y02562*
X04338Y02572*
X04342Y02583*
X04344Y02595*
X04342Y02607*
X04338Y02618*
X04331Y02627*
X04321Y02635*
X0431Y02639*
X04298Y02641*
G37*
G36*
X0418D02*
X04168Y02639D01*
X04157Y02635*
X04148Y02627*
X0414Y02618*
X04136Y02607*
X04134Y02595*
X04136Y02583*
X0414Y02572*
X04148Y02562*
X04157Y02555*
X04168Y02551*
X0418Y02549*
X04192Y02551*
X04203Y02555*
X04212Y02562*
X0422Y02572*
X04224Y02583*
X04226Y02595*
X04224Y02607*
X0422Y02618*
X04212Y02627*
X04203Y02635*
X04192Y02639*
X0418Y02641*
G37*
G36*
X04062D02*
X0405Y02639D01*
X04039Y02635*
X04029Y02627*
X04022Y02618*
X04018Y02607*
X04016Y02595*
X04018Y02583*
X04022Y02572*
X04029Y02562*
X04039Y02555*
X0405Y02551*
X04062Y02549*
X04074Y02551*
X04085Y02555*
X04094Y02562*
X04102Y02572*
X04106Y02583*
X04108Y02595*
X04106Y02607*
X04102Y02618*
X04094Y02627*
X04085Y02635*
X04074Y02639*
X04062Y02641*
G37*
G36*
X06284Y02517D02*
X06278Y02516D01*
X06273Y02512*
X06269Y02507*
X06268Y02501*
X06269Y02494*
X06273Y02489*
X06278Y02485*
X06284Y02484*
X06291Y02485*
X06296Y02489*
X06299Y02494*
X06301Y02501*
X06299Y02507*
X06296Y02512*
X06291Y02516*
X06284Y02517*
G37*
G36*
X0102Y02497D02*
X01014Y02496D01*
X01009Y02492*
X01005Y02487*
X01004Y02481*
X01005Y02474*
X01009Y02469*
X01014Y02465*
X0102Y02464*
X01027Y02465*
X01032Y02469*
X01035Y02474*
X01037Y02481*
X01035Y02487*
X01032Y02492*
X01027Y02496*
X0102Y02497*
G37*
G36*
X02624Y02477D02*
X02618Y02476D01*
X02613Y02472*
X02609Y02467*
X02608Y02461*
X02609Y02454*
X02609Y02454*
X02606Y0245*
X02606Y02451*
X02599Y02452*
X02593Y02451*
X02588Y02447*
X02584Y02442*
X02583Y02436*
X02584Y02431*
X02583Y0243*
X02581Y02427*
X0258Y02427*
X02575Y02428*
X02569Y02427*
X02564Y02423*
X0256Y02418*
X02559Y02412*
X0256Y02405*
X02564Y024*
X02569Y02396*
X02575Y02395*
X02582Y02396*
X02587Y024*
X0259Y02405*
X02592Y02412*
X02591Y02416*
X02591Y02417*
X02594Y0242*
X02595Y0242*
X02599Y02419*
X02606Y0242*
X02611Y02424*
X02614Y02429*
X02616Y02436*
X02614Y02442*
X02614Y02442*
X02618Y02446*
X02618Y02445*
X02624Y02444*
X02631Y02445*
X02636Y02449*
X02639Y02454*
X02641Y02461*
X02639Y02467*
X02636Y02472*
X02631Y02476*
X02624Y02477*
G37*
G36*
X02272Y0248D02*
X02265Y02478D01*
X0226Y02475*
X02256Y0247*
X02255Y02463*
X02256Y02457*
X0226Y02452*
X02265Y02448*
X02272Y02447*
X02278Y02448*
X02283Y02452*
X02287Y02457*
X02288Y02463*
X02287Y0247*
X02283Y02475*
X02278Y02478*
X02272Y0248*
G37*
G36*
X02525Y02479D02*
X02519Y02478D01*
X02514Y02474*
X0251Y02469*
X02509Y02463*
X0251Y02456*
X02514Y02451*
X02519Y02447*
X02525Y02446*
X02532Y02447*
X02537Y02451*
X0254Y02456*
X02542Y02463*
X0254Y02469*
X02537Y02474*
X02532Y02478*
X02525Y02479*
G37*
G36*
X05578Y02534D02*
X05566Y02533D01*
X05555Y02528*
X05545Y02521*
X05538Y02511*
X05533Y025*
X05532Y02489*
X05533Y02477*
X05538Y02466*
X05545Y02456*
X05555Y02449*
X05566Y02444*
X05578Y02443*
X0559Y02444*
X05601Y02449*
X0561Y02456*
X05617Y02466*
X05622Y02477*
X05624Y02489*
X05622Y025*
X05617Y02511*
X0561Y02521*
X05601Y02528*
X0559Y02533*
X05578Y02534*
G37*
G36*
X02948Y02472D02*
X02942Y02471D01*
X02937Y02467*
X02933Y02462*
X02932Y02456*
X02933Y02449*
X02937Y02444*
X02942Y0244*
X02948Y02439*
X02955Y0244*
X0296Y02444*
X02963Y02449*
X02965Y02456*
X02963Y02462*
X0296Y02467*
X02955Y02471*
X02948Y02472*
G37*
G36*
X0299Y02457D02*
X02983Y02456D01*
X02976Y02452*
X02972Y02445*
X02971Y02438*
X02972Y02431*
X02976Y02424*
X02983Y0242*
X0299Y02419*
X02997Y0242*
X03004Y02424*
X03008Y02431*
X03009Y02438*
X03008Y02445*
X03004Y02452*
X02997Y02456*
X0299Y02457*
G37*
G36*
X02203D02*
X02195Y02456D01*
X02189Y02452*
X02185Y02445*
X02183Y02438*
X02185Y02431*
X02189Y02424*
X02195Y0242*
X02203Y02419*
X0221Y0242*
X02216Y02424*
X0222Y02431*
X02222Y02438*
X0222Y02445*
X02216Y02452*
X0221Y02456*
X02203Y02457*
G37*
G36*
X03617Y02553D02*
X03604Y02552D01*
X03592Y02548*
X0358Y02542*
X0357Y02533*
X03561Y02523*
X03555Y02512*
X03551Y02499*
X0355Y02486*
X03551Y02473*
X03555Y0246*
X03561Y02448*
X0357Y02438*
X0358Y0243*
X03592Y02424*
X03604Y0242*
X03617Y02418*
X03631Y0242*
X03643Y02424*
X03655Y0243*
X03665Y02438*
X03673Y02448*
X0368Y0246*
X03684Y02473*
X03685Y02486*
X03684Y02499*
X0368Y02512*
X03673Y02523*
X03665Y02533*
X03655Y02542*
X03643Y02548*
X03631Y02552*
X03617Y02553*
G37*
G36*
X01651D02*
X01638Y02552D01*
X01626Y02548*
X01614Y02542*
X01604Y02533*
X01595Y02523*
X01589Y02512*
X01585Y02499*
X01584Y02486*
X01585Y02473*
X01589Y0246*
X01595Y02448*
X01604Y02438*
X01614Y0243*
X01626Y02424*
X01638Y0242*
X01651Y02418*
X01665Y0242*
X01677Y02424*
X01689Y0243*
X01699Y02438*
X01707Y02448*
X01714Y0246*
X01718Y02473*
X01719Y02486*
X01718Y02499*
X01714Y02512*
X01707Y02523*
X01699Y02533*
X01689Y02542*
X01677Y02548*
X01665Y02552*
X01651Y02553*
G37*
G36*
X00199Y02545D02*
X00187Y02544D01*
X00175Y0254*
X00164Y02534*
X00154Y02526*
X00146Y02516*
X0014Y02505*
X00136Y02493*
X00135Y02481*
X00136Y02468*
X0014Y02456*
X00146Y02445*
X00154Y02435*
X00164Y02427*
X00175Y02421*
X00187Y02417*
X00199Y02416*
X00212Y02417*
X00224Y02421*
X00235Y02427*
X00245Y02435*
X00253Y02445*
X00259Y02456*
X00262Y02468*
X00264Y02481*
X00262Y02493*
X00259Y02505*
X00253Y02516*
X00245Y02526*
X00235Y02534*
X00224Y0254*
X00212Y02544*
X00199Y02545*
G37*
G36*
X02894Y02447D02*
X02888Y02446D01*
X02883Y02442*
X02879Y02437*
X02878Y02431*
X02879Y02424*
X02883Y02419*
X02888Y02415*
X02894Y02414*
X02901Y02415*
X02906Y02419*
X02907*
X02909Y02416*
X02914Y02412*
X0292Y02411*
X02927Y02412*
X02932Y02416*
X02935Y02421*
X02937Y02428*
X02935Y02434*
X02932Y02439*
X02927Y02443*
X0292Y02444*
X02914Y02443*
X02909Y02439*
X02908*
X02906Y02442*
X02901Y02446*
X02894Y02447*
G37*
G36*
X04039Y02422D02*
X04033Y02421D01*
X04028Y02417*
X04024Y02412*
X04023Y02406*
X04024Y02399*
X04028Y02394*
X04033Y0239*
X04039Y02389*
X04046Y0239*
X04051Y02394*
X04054Y02399*
X04056Y02406*
X04054Y02412*
X04051Y02417*
X04046Y02421*
X04039Y02422*
G37*
G36*
X03498Y02357D02*
X03492Y02356D01*
X03487Y02352*
X03483Y02347*
X03482Y02341*
X03483Y02334*
X03487Y02329*
X03492Y02325*
X03498Y02324*
X03505Y02325*
X0351Y02329*
X03513Y02334*
X03515Y02341*
X03513Y02347*
X0351Y02352*
X03505Y02356*
X03498Y02357*
G37*
G36*
X02726Y02309D02*
X0272Y02308D01*
X02715Y02304*
X02713Y02301*
X02709Y02304*
X02702Y02305*
X02696Y02304*
X02691Y023*
X02687Y02295*
X02686Y0229*
X02682Y02291*
X0268Y02297*
X02677Y02302*
X02672Y02306*
X02665Y02307*
X02659Y02306*
X02654Y02302*
X0265Y02297*
X02649Y02291*
X02648Y02289*
X02645Y0229*
X02639Y02289*
X02634Y02285*
X0263Y0228*
X02629Y02274*
X0263Y02267*
X02634Y02262*
X02639Y02258*
X02645Y02257*
X02652Y02258*
X02657Y02262*
X0266Y02267*
X02662Y02274*
X02663Y02275*
X02665Y02274*
X02672Y02275*
X02677Y02279*
X0268Y02284*
X02681Y02289*
X02686Y02289*
X02687Y02282*
X02691Y02277*
X02696Y02273*
X02702Y02272*
X02709Y02273*
X02714Y02277*
X02716Y0228*
X0272Y02277*
X02726Y02276*
X02733Y02277*
X02738Y02281*
X02741Y02286*
X02743Y02293*
X02741Y02299*
X02738Y02304*
X02733Y02308*
X02726Y02309*
G37*
G36*
X02475Y02307D02*
X02469Y02306D01*
X02464Y02302*
X02462Y02299*
X02457Y02297*
X02455Y02297*
X0245Y02298*
X02444Y02297*
X02439Y02293*
X02435Y02288*
X02434Y02282*
X02435Y02275*
X02439Y0227*
X02444Y02266*
X0245Y02265*
X02457Y02266*
X02462Y0227*
X02465Y02275*
X0247Y02275*
X02475Y02274*
X02482Y02275*
X02487Y02279*
X0249Y02284*
X02492Y02291*
X0249Y02297*
X02487Y02302*
X02482Y02306*
X02475Y02307*
G37*
G36*
X02803Y02323D02*
X02797Y02322D01*
X02792Y02318*
X02788Y02313*
X02787Y02307*
X02788Y023*
X02792Y02295*
X02797Y02291*
X02803Y0229*
X0281Y02291*
X02815Y02295*
X02818Y023*
X0282Y02307*
X02818Y02313*
X02815Y02318*
X0281Y02322*
X02803Y02323*
G37*
G36*
X02985Y02303D02*
X02979Y02302D01*
X02974Y02298*
X0297Y02293*
X02969Y02287*
X0297Y0228*
X02974Y02275*
X02979Y02271*
X02985Y0227*
X02992Y02271*
X02997Y02275*
X03Y0228*
X03002Y02287*
X03Y02293*
X02997Y02298*
X02992Y02302*
X02985Y02303*
G37*
G36*
X02942Y02302D02*
X02936Y02301D01*
X02931Y02297*
X02927Y02292*
X02926Y02286*
X02927Y02279*
X02931Y02274*
X02936Y0227*
X02942Y02269*
X02949Y0227*
X02954Y02274*
X02957Y02279*
X02959Y02286*
X02957Y02292*
X02954Y02297*
X02949Y02301*
X02942Y02302*
G37*
G36*
X05327Y02346D02*
X05317Y02345D01*
X05308Y02341*
X053Y02334*
X05294Y02326*
X0529Y02317*
X05288Y02307*
X0529Y02297*
X05294Y02288*
X053Y0228*
X05308Y02273*
X05317Y02269*
X05327Y02268*
X05337Y02269*
X05347Y02273*
X05355Y0228*
X05361Y02288*
X05365Y02297*
X05366Y02307*
X05365Y02317*
X05361Y02326*
X05355Y02334*
X05347Y02341*
X05337Y02345*
X05327Y02346*
G37*
G36*
X04927D02*
X04917Y02345D01*
X04908Y02341*
X049Y02334*
X04894Y02326*
X0489Y02317*
X04888Y02307*
X0489Y02297*
X04894Y02288*
X049Y0228*
X04908Y02273*
X04917Y02269*
X04927Y02268*
X04937Y02269*
X04947Y02273*
X04955Y0228*
X04961Y02288*
X04965Y02297*
X04966Y02307*
X04965Y02317*
X04961Y02326*
X04955Y02334*
X04947Y02341*
X04937Y02345*
X04927Y02346*
G37*
G36*
X04727D02*
X04717Y02345D01*
X04708Y02341*
X047Y02334*
X04694Y02326*
X0469Y02317*
X04688Y02307*
X0469Y02297*
X04694Y02288*
X047Y0228*
X04708Y02273*
X04717Y02269*
X04727Y02268*
X04737Y02269*
X04747Y02273*
X04755Y0228*
X04761Y02288*
X04765Y02297*
X04766Y02307*
X04765Y02317*
X04761Y02326*
X04755Y02334*
X04747Y02341*
X04737Y02345*
X04727Y02346*
G37*
G36*
X04327D02*
X04317Y02345D01*
X04308Y02341*
X043Y02334*
X04294Y02326*
X0429Y02317*
X04288Y02307*
X0429Y02297*
X04294Y02288*
X043Y0228*
X04308Y02273*
X04317Y02269*
X04327Y02268*
X04337Y02269*
X04347Y02273*
X04355Y0228*
X04361Y02288*
X04365Y02297*
X04366Y02307*
X04365Y02317*
X04361Y02326*
X04355Y02334*
X04347Y02341*
X04337Y02345*
X04327Y02346*
G37*
G36*
X02409Y0233D02*
X02403Y02329D01*
X02398Y02325*
X02394Y0232*
X02393Y02314*
X02394Y02307*
X02398Y02302*
X02399Y02301*
Y02295*
X02398Y02294*
X02394Y02289*
X02393Y02283*
X02394Y02276*
X02398Y02271*
X02403Y02267*
X02409Y02266*
X02416Y02267*
X02421Y02271*
X02424Y02276*
X02426Y02283*
X02424Y02289*
X02421Y02294*
X02419Y02295*
Y02301*
X02421Y02302*
X02424Y02307*
X02426Y02314*
X02424Y0232*
X02421Y02325*
X02416Y02329*
X02409Y0233*
G37*
G36*
X02579Y02297D02*
X02573Y02296D01*
X02568Y02292*
X02564Y02287*
X02563Y02281*
X02564Y02274*
X02568Y02269*
X02573Y02265*
X02579Y02264*
X02586Y02265*
X02591Y02269*
X02594Y02274*
X02596Y02281*
X02594Y02287*
X02591Y02292*
X02586Y02296*
X02579Y02297*
G37*
G36*
X03342Y02279D02*
X03336Y02278D01*
X03331Y02274*
X03327Y02269*
X03326Y02263*
X03327Y02256*
X03331Y02251*
X03336Y02247*
X03342Y02246*
X03349Y02247*
X03354Y02251*
X03357Y02256*
X03359Y02263*
X03357Y02269*
X03354Y02274*
X03349Y02278*
X03342Y02279*
G37*
G36*
X02841D02*
X02835Y02278D01*
X0283Y02274*
X02826Y02269*
X02825Y02263*
X02826Y02256*
X0283Y02251*
X02835Y02247*
X02841Y02246*
X02848Y02247*
X02853Y02251*
X02856Y02256*
X02858Y02263*
X02856Y02269*
X02853Y02274*
X02848Y02278*
X02841Y02279*
G37*
G36*
X00996Y02272D02*
X0099Y02271D01*
X00985Y02267*
X00981Y02262*
X0098Y02256*
X00981Y02249*
X00985Y02244*
X0099Y0224*
X00996Y02239*
X01003Y0224*
X01008Y02244*
X01011Y02249*
X01013Y02256*
X01011Y02262*
X01008Y02267*
X01003Y02271*
X00996Y02272*
G37*
G36*
X05634Y02252D02*
X05628Y02251D01*
X05623Y02247*
X05619Y02242*
X05618Y02236*
X05619Y02229*
X05623Y02224*
X05628Y0222*
X05634Y02219*
X05641Y0222*
X05646Y02224*
X05649Y02229*
X05651Y02236*
X05649Y02242*
X05646Y02247*
X05641Y02251*
X05634Y02252*
G37*
G36*
X02499D02*
X02493Y02251D01*
X02488Y02247*
X02484Y02242*
X02483Y02236*
X02484Y02229*
X02488Y02224*
X02493Y0222*
X02499Y02219*
X02506Y0222*
X02511Y02224*
X02514Y02229*
X02516Y02236*
X02514Y02242*
X02511Y02247*
X02506Y02251*
X02499Y02252*
G37*
G36*
X0233Y02231D02*
X02324Y0223D01*
X02319Y02226*
X02315Y02221*
X02314Y02215*
X02315Y02208*
X02319Y02203*
X02324Y02199*
X0233Y02198*
X02337Y02199*
X02342Y02203*
X02345Y02208*
X02347Y02215*
X02345Y02221*
X02342Y02226*
X02337Y0223*
X0233Y02231*
G37*
G36*
X05577Y0223D02*
X05571Y02229D01*
X05566Y02225*
X05562Y0222*
X05561Y02214*
X05562Y02207*
X05566Y02202*
X05571Y02198*
X05577Y02197*
X05584Y02198*
X05589Y02202*
X05592Y02207*
X05594Y02214*
X05592Y0222*
X05589Y02225*
X05584Y02229*
X05577Y0223*
G37*
G36*
X06424Y02197D02*
X06418Y02196D01*
X06413Y02192*
X06409Y02187*
X06408Y02181*
X06409Y02174*
X06413Y02169*
X06418Y02165*
X06424Y02164*
X06431Y02165*
X06436Y02169*
X06439Y02174*
X06441Y02181*
X06439Y02187*
X06436Y02192*
X06431Y02196*
X06424Y02197*
G37*
G36*
X01754Y02142D02*
X01748Y02141D01*
X01743Y02137*
X01739Y02132*
X01738Y02126*
X01739Y02119*
X01743Y02114*
X01748Y0211*
X01754Y02109*
X01761Y0211*
X01766Y02114*
X01769Y02119*
X01771Y02126*
X01769Y02132*
X01766Y02137*
X01761Y02141*
X01754Y02142*
G37*
G36*
X01619Y02137D02*
X01613Y02136D01*
X01608Y02132*
X01604Y02127*
X01603Y02121*
X01604Y02114*
X01608Y02109*
X01613Y02105*
X01619Y02104*
X01626Y02105*
X01631Y02109*
X01634Y02114*
X01636Y02121*
X01634Y02127*
X01631Y02132*
X01626Y02136*
X01619Y02137*
G37*
G36*
X01696Y02116D02*
X01689Y02114D01*
X01683Y0211*
X01679Y02104*
X01677Y02097*
X01679Y02089*
X01683Y02083*
X01689Y02079*
X01696Y02078*
X01704Y02079*
X0171Y02083*
X01714Y02089*
X01716Y02097*
X01714Y02104*
X0171Y0211*
X01704Y02114*
X01696Y02116*
G37*
G36*
X01884Y02087D02*
X01878Y02086D01*
X01873Y02082*
X01869Y02077*
X01868Y02071*
X01869Y02064*
X01873Y02059*
X01878Y02055*
X01884Y02054*
X01891Y02055*
X01896Y02059*
X01899Y02064*
X01901Y02071*
X01899Y02077*
X01896Y02082*
X01891Y02086*
X01884Y02087*
G37*
G36*
X01568Y02084D02*
X01561Y02082D01*
X01556Y02079*
X01553Y02073*
X01551Y02067*
X01553Y02061*
X01556Y02056*
X01561Y02052*
X01568Y02051*
X01574Y02052*
X01579Y02056*
X01583Y02061*
X01584Y02067*
X01583Y02073*
X01579Y02079*
X01574Y02082*
X01568Y02084*
G37*
G36*
X03571Y02116D02*
X03564Y02114D01*
X03558Y0211*
X03554Y02104*
X03552Y02097*
X03554Y02089*
X03558Y02083*
X03564Y02079*
X03568Y02078*
Y02073*
X03565Y02073*
X0356Y02069*
X03556Y02064*
X03555Y02058*
X03556Y02051*
X03558Y02049*
X03559Y02045*
X03558Y02041*
X03556Y02039*
X03555Y02033*
X03556Y02026*
X0356Y02021*
X03565Y02017*
X03571Y02016*
X03578Y02017*
X03583Y02021*
X03586Y02026*
X03588Y02033*
X03586Y02039*
X03585Y02041*
X03583Y02045*
X03585Y02049*
X03586Y02051*
X03588Y02058*
X03586Y02064*
X03583Y02069*
X03578Y02073*
X03575Y02073*
Y02078*
X03579Y02079*
X03585Y02083*
X03589Y02089*
X0359Y02097*
X03589Y02104*
X03585Y0211*
X03579Y02114*
X03571Y02116*
G37*
G36*
X02409Y01983D02*
X02403Y01982D01*
X02398Y01978*
X02394Y01973*
X02393Y01967*
X02394Y0196*
X02396Y01958*
X02392Y01955*
X02391Y01956*
X02384Y01957*
X02378Y01956*
X02373Y01952*
X02369Y01947*
X02368Y01941*
X02369Y01934*
X02373Y01929*
X02378Y01925*
X02384Y01924*
X02391Y01925*
X02396Y01929*
X02399Y01934*
X02401Y01941*
X02399Y01947*
X02398Y01949*
X02402Y01952*
X02403Y01951*
X02409Y0195*
X02416Y01951*
X02421Y01955*
X02424Y0196*
X02426Y01967*
X02424Y01973*
X02421Y01978*
X02416Y01982*
X02409Y01983*
G37*
G36*
X03298Y01987D02*
X03292Y01986D01*
X03287Y01982*
X03283Y01977*
X03282Y01971*
X03283Y01964*
X03287Y01959*
X03292Y01955*
X03298Y01954*
X03305Y01955*
X0331Y01959*
X03313Y01964*
X03315Y01971*
X03313Y01977*
X0331Y01982*
X03305Y01986*
X03298Y01987*
G37*
G36*
X01009Y01972D02*
X01003Y01971D01*
X00998Y01967*
X00994Y01962*
X00993Y01956*
X00994Y01949*
X00998Y01944*
X01003Y0194*
X01009Y01939*
X01016Y0194*
X01021Y01944*
X01024Y01949*
X01026Y01956*
X01024Y01962*
X01021Y01967*
X01016Y01971*
X01009Y01972*
G37*
G36*
X02299Y01932D02*
X02293Y01931D01*
X02288Y01927*
X02284Y01922*
X02283Y01916*
X02284Y01909*
X02288Y01904*
X02293Y019*
X02299Y01899*
X02306Y019*
X02311Y01904*
X02314Y01909*
X02316Y01916*
X02314Y01922*
X02311Y01927*
X02306Y01931*
X02299Y01932*
G37*
G36*
X00199Y0202D02*
X00187Y02019D01*
X00175Y02015*
X00164Y02009*
X00154Y02001*
X00146Y01991*
X0014Y0198*
X00136Y01968*
X00135Y01956*
X00136Y01943*
X0014Y01931*
X00146Y0192*
X00154Y0191*
X00164Y01902*
X00175Y01896*
X00187Y01892*
X00199Y01891*
X00212Y01892*
X00224Y01896*
X00235Y01902*
X00245Y0191*
X00253Y0192*
X00259Y01931*
X00262Y01943*
X00264Y01956*
X00262Y01968*
X00259Y0198*
X00253Y01991*
X00245Y02001*
X00235Y02009*
X00224Y02015*
X00212Y02019*
X00199Y0202*
G37*
G36*
X03554Y01907D02*
X03548Y01906D01*
X03543Y01902*
X03539Y01897*
X03538Y01891*
X03539Y01884*
X03543Y01879*
X03548Y01875*
X03554Y01874*
X03561Y01875*
X03566Y01879*
X03569Y01884*
X03571Y01891*
X03569Y01897*
X03566Y01902*
X03561Y01906*
X03554Y01907*
G37*
G36*
X03392Y01887D02*
X03386Y01886D01*
X03381Y01882*
X03377Y01877*
X03376Y01871*
X03377Y01864*
X03381Y01859*
X03386Y01855*
X03392Y01854*
X03399Y01855*
X03404Y01859*
X03407Y01864*
X03409Y01871*
X03407Y01877*
X03404Y01882*
X03399Y01886*
X03392Y01887*
G37*
G36*
X03439Y01887D02*
X03433Y01886D01*
X03427Y01882*
X03424Y01877*
X03422Y0187*
X03424Y01864*
X03427Y01859*
X03433Y01855*
X03439Y01854*
X03445Y01855*
X0345Y01859*
X03454Y01864*
X03455Y0187*
X03454Y01877*
X0345Y01882*
X03445Y01886*
X03439Y01887*
G37*
G36*
X03804Y01856D02*
X03798Y01855D01*
X03793Y01851*
X03789Y01846*
X03788Y0184*
X03789Y01833*
X03793Y01828*
X03798Y01824*
X03804Y01823*
X03811Y01824*
X03816Y01828*
X03819Y01833*
X03821Y0184*
X03819Y01846*
X03816Y01851*
X03811Y01855*
X03804Y01856*
G37*
G36*
X03329Y01842D02*
X03322Y01841D01*
X03317Y01837*
X03314Y01832*
X03312Y01826*
X03314Y01819*
X03317Y01814*
X03322Y0181*
X03329Y01809*
X03335Y0181*
X0334Y01814*
X03344Y01819*
X03345Y01826*
X03344Y01832*
X0334Y01837*
X03335Y01841*
X03329Y01842*
G37*
G36*
X01393Y01833D02*
X01387Y01832D01*
X01382Y01828*
X01378Y01823*
X01377Y01816*
X01378Y0181*
X01382Y01805*
X01387Y01801*
X01393Y018*
X01399Y01801*
X01405Y01805*
X01408Y0181*
X0141Y01816*
X01408Y01823*
X01405Y01828*
X01399Y01832*
X01393Y01833*
G37*
G36*
X03944Y01832D02*
X03938Y01831D01*
X03933Y01827*
X03929Y01822*
X03928Y01816*
X03929Y01809*
X03933Y01804*
X03938Y018*
X03944Y01799*
X03951Y018*
X03956Y01804*
X03959Y01809*
X03961Y01816*
X03959Y01822*
X03956Y01827*
X03951Y01831*
X03944Y01832*
G37*
G36*
X03056Y01828D02*
X0305Y01826D01*
X03045Y01823*
X03041Y01818*
X0304Y01811*
X03041Y01805*
X03045Y018*
X0305Y01796*
X03056Y01795*
X03063Y01796*
X03068Y018*
X03071Y01805*
X03073Y01811*
X03071Y01818*
X03068Y01823*
X03063Y01826*
X03056Y01828*
G37*
G36*
X01879D02*
X01873Y01826D01*
X01868Y01823*
X01864Y01818*
X01863Y01811*
X01864Y01805*
X01868Y018*
X01873Y01796*
X01879Y01795*
X01886Y01796*
X01891Y018*
X01895Y01805*
X01896Y01811*
X01895Y01818*
X01891Y01823*
X01886Y01826*
X01879Y01828*
G37*
G36*
X04064Y01812D02*
X04058Y01811D01*
X04053Y01807*
X04049Y01802*
X04048Y01796*
X04049Y01789*
X04053Y01784*
X04058Y0178*
X04064Y01779*
X04071Y0178*
X04076Y01784*
X04079Y01789*
X04081Y01796*
X04079Y01802*
X04076Y01807*
X04071Y01811*
X04064Y01812*
G37*
G36*
X02579Y01806D02*
X02573Y01805D01*
X02568Y01801*
X02564Y01796*
X02563Y0179*
X02564Y01783*
X02568Y01778*
X02573Y01774*
X02579Y01773*
X02586Y01774*
X02591Y01778*
X02594Y01783*
X02596Y0179*
X02594Y01796*
X02591Y01801*
X02586Y01805*
X02579Y01806*
G37*
G36*
X02626Y01786D02*
X0262Y01785D01*
X02615Y01781*
X02611Y01776*
X0261Y0177*
X02611Y01763*
X02615Y01758*
X0262Y01754*
X02626Y01753*
X02633Y01754*
X02638Y01758*
X02641Y01763*
X02643Y0177*
X02641Y01776*
X02638Y01781*
X02633Y01785*
X02626Y01786*
G37*
G36*
X03719Y01782D02*
X03713Y01781D01*
X03708Y01777*
X03704Y01772*
X03703Y01766*
X03704Y01759*
X03708Y01754*
X03713Y0175*
X03719Y01749*
X03726Y0175*
X03731Y01754*
X03734Y01759*
X03736Y01766*
X03734Y01772*
X03731Y01777*
X03726Y01781*
X03719Y01782*
G37*
G36*
X02549Y01771D02*
X02543Y0177D01*
X02538Y01766*
X02534Y01761*
X02533Y01755*
X02534Y01748*
X02538Y01743*
X02543Y01739*
X02549Y01738*
X02556Y01739*
X02561Y01743*
X02564Y01748*
X02566Y01755*
X02564Y01761*
X02561Y01766*
X02556Y0177*
X02549Y01771*
G37*
G36*
X04134Y01767D02*
X04128Y01766D01*
X04123Y01762*
X04119Y01757*
X04118Y01751*
X04119Y01744*
X04123Y01739*
X04128Y01735*
X04134Y01734*
X04141Y01735*
X04146Y01739*
X04149Y01744*
X04151Y01751*
X04149Y01757*
X04146Y01762*
X04141Y01766*
X04134Y01767*
G37*
G36*
X02604Y0175D02*
X02598Y01749D01*
X02593Y01745*
X02589Y0174*
X02588Y01734*
X02589Y01727*
X02593Y01722*
X02598Y01718*
X02604Y01717*
X02611Y01718*
X02616Y01722*
X02619Y01727*
X02621Y01734*
X02619Y0174*
X02616Y01745*
X02611Y01749*
X02604Y0175*
G37*
G36*
X00988Y01733D02*
X00981Y01732D01*
X00976Y01729*
X00973Y01723*
X00971Y01717*
X00973Y01711*
X00976Y01705*
X00981Y01702*
X00988Y01701*
X00994Y01702*
X00999Y01705*
X01003Y01711*
X01004Y01717*
X01003Y01723*
X00999Y01729*
X00994Y01732*
X00988Y01733*
G37*
G36*
X03197Y0173D02*
X03191Y01729D01*
X03185Y01725*
X03182Y0172*
X0318Y01714*
X03182Y01707*
X03185Y01702*
X03191Y01698*
X03197Y01697*
X03203Y01698*
X03208Y01702*
X03212Y01707*
X03213Y01714*
X03212Y0172*
X03208Y01725*
X03203Y01729*
X03197Y0173*
G37*
G36*
X03589Y01727D02*
X03583Y01726D01*
X03578Y01722*
X03574Y01717*
X03573Y01711*
X03574Y01704*
X03578Y01699*
X03583Y01695*
X03589Y01694*
X03596Y01695*
X03601Y01699*
X03604Y01704*
X03606Y01711*
X03604Y01717*
X03601Y01722*
X03596Y01726*
X03589Y01727*
G37*
G36*
X01893Y01709D02*
X01887Y01708D01*
X01882Y01704*
X01878Y01699*
X01877Y01693*
X01878Y01686*
X01882Y01681*
X01887Y01677*
X01893Y01676*
X019Y01677*
X01905Y01681*
X01908Y01686*
X0191Y01693*
X01908Y01699*
X01905Y01704*
X019Y01708*
X01893Y01709*
G37*
G36*
X03803Y01707D02*
X03797Y01706D01*
X03792Y01702*
X03788Y01697*
X03787Y01691*
X03788Y01684*
X03792Y01679*
X03797Y01675*
X03803Y01674*
X0381Y01675*
X03815Y01679*
X03818Y01684*
X0382Y01691*
X03818Y01697*
X03815Y01702*
X0381Y01706*
X03803Y01707*
G37*
G36*
X03724Y01691D02*
X03718Y0169D01*
X03713Y01686*
X03709Y01681*
X03708Y01675*
X03709Y01668*
X03713Y01663*
X03718Y01659*
X03724Y01658*
X03731Y01659*
X03736Y01663*
X03739Y01668*
X03741Y01675*
X03739Y01681*
X03736Y01686*
X03731Y0169*
X03724Y01691*
G37*
G36*
X01822Y0169D02*
X01816Y01689D01*
X01811Y01685*
X01807Y0168*
X01806Y01674*
X01807Y01667*
X01811Y01662*
X01816Y01658*
X01822Y01657*
X01829Y01658*
X01834Y01662*
X01837Y01667*
X01839Y01674*
X01837Y0168*
X01834Y01685*
X01829Y01689*
X01822Y0169*
G37*
G36*
X03773Y01682D02*
X03767Y01681D01*
X03762Y01677*
X03758Y01672*
X03757Y01666*
X03758Y01659*
X03762Y01654*
X03767Y01651*
X03773Y01649*
X0378Y01651*
X03785Y01654*
X03788Y01659*
X0379Y01666*
X03788Y01672*
X03785Y01677*
X0378Y01681*
X03773Y01682*
G37*
G36*
X06844Y01677D02*
X06838Y01676D01*
X06833Y01672*
X06829Y01667*
X06828Y01661*
X06829Y01654*
X06833Y01649*
X06838Y01645*
X06844Y01644*
X06851Y01645*
X06856Y01649*
X06859Y01654*
X06861Y01661*
X06859Y01667*
X06856Y01672*
X06851Y01676*
X06844Y01677*
G37*
G36*
X03224Y01677D02*
X03218Y01676D01*
X03213Y01672*
X03209Y01667*
X03208Y01661*
X03209Y01655*
X03213Y01649*
X03218Y01646*
X03224Y01645*
X03231Y01646*
X03235Y01649*
X03239Y01649*
X03241Y01649*
X03246Y01645*
X03252Y01644*
X03259Y01645*
X03264Y01649*
X03267Y01654*
X03269Y01661*
X03267Y01667*
X03264Y01672*
X03259Y01676*
X03252Y01677*
X03246Y01676*
X03242Y01673*
X03238Y01672*
X03235Y01673*
X03231Y01676*
X03224Y01677*
G37*
G36*
X02666Y01656D02*
X0266Y01655D01*
X02655Y01651*
X02651Y01646*
X0265Y0164*
X02651Y01635*
X02647Y01631*
X02647Y01631*
X02643Y01632*
X02637Y01631*
X02632Y01627*
X02628Y01622*
X02627Y01616*
X02628Y01609*
X02632Y01604*
X02637Y016*
X02643Y01599*
X0265Y016*
X02655Y01604*
X02658Y01609*
X0266Y01616*
X02659Y0162*
X02662Y01624*
X02663Y01624*
X02666Y01623*
X02673Y01624*
X02678Y01628*
X02681Y01633*
X02683Y0164*
X02681Y01646*
X02678Y01651*
X02673Y01655*
X02666Y01656*
G37*
G36*
X04134Y01667D02*
X04128Y01666D01*
X04123Y01662*
X04119Y01657*
X04118Y01651*
X04119Y01644*
X04123Y01639*
X04128Y01635*
X04133Y01634*
X04135Y01631*
X04136Y01629*
X04136Y01629*
X04134Y01623*
X04136Y01617*
X04139Y01612*
X04145Y01608*
X04151Y01607*
X04157Y01608*
X04161Y01611*
X04164Y01607*
X04164Y01607*
X04163Y01601*
X04164Y01594*
X04168Y01589*
X04173Y01585*
X04179Y01584*
X04186Y01585*
X04191Y01589*
X04194Y01594*
X04196Y01601*
X04194Y01607*
X04191Y01612*
X04186Y01616*
X04179Y01617*
X04173Y01616*
X04169Y01613*
X04166Y01617*
X04166Y01617*
X04167Y01623*
X04166Y01629*
X04162Y01635*
X04157Y01638*
X04152Y01639*
X0415Y01643*
X04149Y01644*
X04149Y01644*
X04151Y01651*
X04149Y01657*
X04146Y01662*
X04141Y01666*
X04134Y01667*
G37*
G36*
X02719Y01607D02*
X02713Y01606D01*
X02708Y01602*
X02704Y01597*
X02703Y01591*
X02704Y01584*
X02708Y01579*
X02713Y01575*
X02719Y01574*
X02726Y01575*
X02731Y01579*
X02734Y01584*
X02736Y01591*
X02734Y01597*
X02731Y01602*
X02726Y01606*
X02719Y01607*
G37*
G36*
X03894Y01582D02*
X03888Y01581D01*
X03883Y01577*
X03879Y01572*
X03878Y01566*
X03879Y01559*
X03883Y01554*
X03888Y0155*
X03894Y01549*
X03901Y0155*
X03906Y01554*
X03909Y01559*
X03911Y01566*
X03909Y01572*
X03906Y01577*
X03901Y01581*
X03894Y01582*
G37*
G36*
X03969Y01568D02*
X03963Y01567D01*
X03958Y01563*
X03954Y01558*
X03953Y01552*
X03954Y01545*
X03958Y0154*
X03963Y01536*
X03969Y01535*
X03976Y01536*
X03978Y01538*
X03983Y01539*
X03985Y01537*
X03988Y01535*
X03994Y01534*
X04001Y01535*
X04006Y01539*
X04009Y01544*
X04011Y01551*
X04009Y01557*
X04006Y01562*
X04001Y01566*
X03994Y01567*
X03988Y01566*
X03983Y01562*
X03982*
X03981Y01563*
X03976Y01567*
X03969Y01568*
G37*
G36*
X04034Y01562D02*
X04028Y01561D01*
X04023Y01557*
X04019Y01552*
X04018Y01546*
X04019Y01539*
X04023Y01534*
X04028Y0153*
X04034Y01529*
X04041Y0153*
X04046Y01534*
X04049Y01539*
X04051Y01546*
X04049Y01552*
X04046Y01557*
X04041Y01561*
X04034Y01562*
G37*
G36*
X03924Y01552D02*
X03918Y01551D01*
X03913Y01547*
X03909Y01542*
X03908Y01536*
X03909Y01529*
X03913Y01524*
X03918Y0152*
X03924Y01519*
X03931Y0152*
X03936Y01524*
X03939Y01529*
X03941Y01536*
X03939Y01542*
X03936Y01547*
X03931Y01551*
X03924Y01552*
G37*
G36*
X02894Y01577D02*
X02888Y01576D01*
X02883Y01572*
X02879Y01567*
X02878Y01561*
X02879Y01554*
X02883Y01549*
X02888Y01545*
X02894Y01544*
X02901Y01545*
X02901Y01546*
X02904Y01542*
X02904Y01542*
X02903Y01536*
X02904Y01529*
X02908Y01524*
X02913Y0152*
X02919Y01519*
X02926Y0152*
X02931Y01524*
X02934Y01529*
X02936Y01536*
X02934Y01542*
X02931Y01547*
X02926Y01551*
X02919Y01552*
X02913Y01551*
X02913Y0155*
X02909Y01554*
X02909Y01554*
X02911Y01561*
X02909Y01567*
X02906Y01572*
X02901Y01576*
X02894Y01577*
G37*
G36*
X01719Y01552D02*
X01713Y01551D01*
X01708Y01547*
X01704Y01542*
X01703Y01536*
X01704Y01529*
X01708Y01524*
X01713Y0152*
X01719Y01519*
X01726Y0152*
X01731Y01524*
X01734Y01529*
X01736Y01536*
X01734Y01542*
X01731Y01547*
X01726Y01551*
X01719Y01552*
G37*
G36*
X01897Y01532D02*
X01891Y01531D01*
X01885Y01528*
X01882Y01522*
X0188Y01516*
X01882Y0151*
X01885Y01504*
X01891Y01501*
X01897Y015*
X01903Y01501*
X01908Y01504*
X01912Y0151*
X01913Y01516*
X01912Y01522*
X01908Y01528*
X01903Y01531*
X01897Y01532*
G37*
G36*
X04064Y01527D02*
X04058Y01526D01*
X04053Y01522*
X04049Y01517*
X04048Y01511*
X04049Y01504*
X04053Y01499*
X04058Y01495*
X04064Y01494*
X04071Y01495*
X04076Y01499*
X04079Y01504*
X04081Y01511*
X04079Y01517*
X04076Y01522*
X04071Y01526*
X04064Y01527*
G37*
G36*
X03864D02*
X03858Y01526D01*
X03853Y01522*
X03849Y01517*
X03848Y01511*
X03849Y01504*
X03853Y01499*
X03858Y01495*
X03864Y01494*
X03871Y01495*
X03876Y01499*
X03879Y01504*
X03881Y01511*
X03879Y01517*
X03876Y01522*
X03871Y01526*
X03864Y01527*
G37*
G36*
X02274Y01522D02*
X02268Y01521D01*
X02263Y01517*
X02259Y01512*
X02258Y01506*
X02259Y01499*
X02263Y01494*
X02268Y0149*
X02274Y01489*
X02281Y0149*
X02286Y01494*
X02289Y01499*
X02291Y01506*
X02289Y01512*
X02286Y01517*
X02281Y01521*
X02274Y01522*
G37*
G36*
X03834Y01497D02*
X03828Y01496D01*
X03823Y01492*
X03819Y01487*
X03818Y01481*
X03819Y01474*
X03823Y01469*
X03828Y01465*
X03834Y01464*
X03841Y01465*
X03846Y01469*
X03849Y01474*
X03851Y01481*
X03849Y01487*
X03846Y01492*
X03841Y01496*
X03834Y01497*
G37*
G36*
X02694D02*
X02688Y01496D01*
X02683Y01492*
X02679Y01487*
X02678Y01481*
X02679Y01474*
X02683Y01469*
X02688Y01465*
X02694Y01464*
X02701Y01465*
X02706Y01469*
X02709Y01474*
X02711Y01481*
X02709Y01487*
X02706Y01492*
X02701Y01496*
X02694Y01497*
G37*
G36*
X03549Y01457D02*
X03543Y01456D01*
X03538Y01452*
X03534Y01447*
X03533Y01441*
X03534Y01434*
X03538Y01429*
X03543Y01425*
X03549Y01424*
X03556Y01425*
X03561Y01429*
X03564Y01434*
X03566Y01441*
X03564Y01447*
X03561Y01452*
X03556Y01456*
X03549Y01457*
G37*
G36*
X02446Y01453D02*
X0244Y01452D01*
X02435Y01448*
X02431Y01443*
X0243Y01437*
X02431Y0143*
X02435Y01425*
X0244Y01421*
X02446Y0142*
X02453Y01421*
X02458Y01425*
X02461Y0143*
X02463Y01437*
X02461Y01443*
X02458Y01448*
X02453Y01452*
X02446Y01453*
G37*
G36*
X01008Y01446D02*
X01002Y01445D01*
X00997Y01441*
X00993Y01436*
X00992Y0143*
X00993Y01423*
X00997Y01418*
X01002Y01414*
X01008Y01413*
X01015Y01414*
X0102Y01418*
X01023Y01423*
X01025Y0143*
X01023Y01436*
X0102Y01441*
X01015Y01445*
X01008Y01446*
G37*
G36*
X02083Y01427D02*
X02077Y01426D01*
X02072Y01423*
X02068Y01417*
X02067Y01411*
X02068Y01405*
X02068Y01405*
X02066Y01402*
X02065Y01401*
X02059Y01402*
X02053Y01401*
X02048Y01397*
X02044Y01392*
X02043Y01386*
X02044Y01379*
X02048Y01374*
X02053Y0137*
X02059Y01369*
X02066Y0137*
X02071Y01374*
X02074Y01379*
X02076Y01386*
X02074Y01392*
X02074Y01392*
X02076Y01395*
X02078Y01396*
X02083Y01395*
X0209Y01396*
X02095Y014*
X02098Y01405*
X021Y01411*
X02098Y01417*
X02095Y01423*
X0209Y01426*
X02083Y01427*
G37*
G36*
X03407Y01427D02*
X03401Y01426D01*
X03395Y01422*
X03392Y01417*
X0339Y01411*
X03392Y01405*
X03395Y014*
X03391Y01397*
X03386Y01401*
X03379Y01402*
X03373Y01401*
X03368Y01397*
X03364Y01392*
X03363Y01386*
X03364Y01379*
X03368Y01374*
X03373Y0137*
X03379Y01369*
X03385Y0137*
X03388Y01368*
X03389Y01367*
X03388Y01363*
X03389Y01357*
X03392Y01353*
X03392Y01352*
X03389Y01349*
X03388Y01349*
X03386Y01351*
X03379Y01352*
X03373Y01351*
X03368Y01347*
X03364Y01342*
X03363Y01336*
X03364Y01329*
X03368Y01324*
X03373Y0132*
X03379Y01319*
X03386Y0132*
X03391Y01324*
X03394Y01329*
X03396Y01336*
X03394Y01342*
X03392Y01345*
X03392Y01346*
X03395Y0135*
X03396Y01349*
X03398Y01348*
X03404Y01347*
X03411Y01348*
X03416Y01351*
X03419Y01357*
X03421Y01363*
X03419Y01369*
X03416Y01374*
X03411Y01378*
X03404Y01379*
X03399Y01378*
X03396Y0138*
X03395Y01382*
X03396Y01386*
X03394Y01392*
X03391Y01396*
X03395Y01399*
X03401Y01396*
X03407Y01395*
X03413Y01396*
X03418Y01399*
X03422Y01405*
X03423Y01411*
X03422Y01417*
X03418Y01422*
X03413Y01426*
X03407Y01427*
G37*
G36*
X00199Y01495D02*
X00187Y01494D01*
X00175Y0149*
X00164Y01484*
X00154Y01476*
X00146Y01466*
X0014Y01455*
X00136Y01443*
X00135Y01431*
X00136Y01418*
X0014Y01406*
X00146Y01395*
X00154Y01385*
X00164Y01377*
X00175Y01371*
X00187Y01367*
X00199Y01366*
X00212Y01367*
X00224Y01371*
X00235Y01377*
X00245Y01385*
X00253Y01395*
X00259Y01406*
X00262Y01418*
X00264Y01431*
X00262Y01443*
X00259Y01455*
X00253Y01466*
X00245Y01476*
X00235Y01484*
X00224Y0149*
X00212Y01494*
X00199Y01495*
G37*
G36*
X02028Y01377D02*
X02022Y01376D01*
X02017Y01373*
X02013Y01367*
X02012Y01361*
X02013Y01355*
X02013Y01355*
X02011Y01352*
X0201Y01351*
X02004Y01352*
X01998Y01351*
X01993Y01347*
X01989Y01342*
X01988Y01336*
X01989Y01329*
X01993Y01324*
X01998Y0132*
X02004Y01319*
X02011Y0132*
X02016Y01324*
X02019Y01329*
X02021Y01336*
X02019Y01342*
X02019Y01342*
X02021Y01345*
X02023Y01346*
X02028Y01345*
X02035Y01346*
X0204Y0135*
X02043Y01355*
X02045Y01361*
X02043Y01367*
X0204Y01373*
X02035Y01376*
X02028Y01377*
G37*
G36*
X02502Y01332D02*
X02496Y01331D01*
X02491Y01327*
X02487Y01322*
X02486Y01316*
X02487Y01309*
X02491Y01304*
X02496Y013*
X02502Y01299*
X02509Y013*
X02514Y01304*
X02517Y01309*
X02519Y01316*
X02517Y01322*
X02514Y01327*
X02509Y01331*
X02502Y01332*
G37*
G36*
X01696Y01329D02*
X01689Y01327D01*
X01683Y01323*
X01679Y01317*
X01677Y01309*
X01679Y01302*
X01683Y01296*
X01689Y01292*
X01696Y0129*
X01704Y01292*
X0171Y01296*
X01714Y01302*
X01716Y01309*
X01714Y01317*
X0171Y01323*
X01704Y01327*
X01696Y01329*
G37*
G36*
X03571Y01328D02*
X03564Y01327D01*
X03558Y01323*
X03554Y01317*
X03552Y01309*
X03554Y01302*
X03558Y01296*
X03564Y01292*
X03571Y0129*
X03579Y01292*
X03585Y01296*
X03589Y01302*
X0359Y01309*
X03589Y01317*
X03585Y01323*
X03579Y01327*
X03571Y01328*
G37*
G36*
X01798Y0132D02*
X01791Y01319D01*
X01786Y01315*
X01783Y0131*
X01781Y01304*
X01783Y01297*
X01786Y01292*
X01791Y01289*
X01798Y01287*
X01804Y01289*
X01809Y01292*
X01813Y01297*
X01814Y01304*
X01813Y0131*
X01809Y01315*
X01804Y01319*
X01798Y0132*
G37*
G36*
X02206Y01314D02*
X022Y01313D01*
X02195Y01309*
X02191Y01304*
X0219Y01298*
X02191Y01291*
X02195Y01286*
X022Y01282*
X02206Y01281*
X02213Y01282*
X02218Y01286*
X02221Y01291*
X02223Y01298*
X02221Y01304*
X02218Y01309*
X02213Y01313*
X02206Y01314*
G37*
G36*
X01567Y01301D02*
X01561Y013D01*
X01556Y01296*
X01552Y01291*
X01551Y01285*
X01552Y01279*
X01556Y01273*
X01561Y0127*
X01567Y01269*
X01574Y0127*
X01579Y01273*
X01582Y01279*
X01584Y01285*
X01582Y01291*
X01579Y01296*
X01574Y013*
X01567Y01301*
G37*
G36*
X00996Y01203D02*
X00989Y01202D01*
X00984Y01198*
X0098Y01193*
X00979Y01187*
X0098Y0118*
X00984Y01175*
X00989Y01171*
X00996Y0117*
X01002Y01171*
X01007Y01175*
X01011Y0118*
X01012Y01187*
X01011Y01193*
X01007Y01198*
X01002Y01202*
X00996Y01203*
G37*
G36*
X02826Y00992D02*
X0282Y00991D01*
X02815Y00987*
X0281*
X02805Y00991*
X02799Y00992*
X02792Y00991*
X02787Y00987*
X02786Y00986*
X0278*
X02779Y00987*
X02773Y00991*
X02767Y00992*
X02761Y00991*
X02756Y00987*
X02751*
X02746Y00991*
X0274Y00992*
X02733Y00991*
X02728Y00987*
X02727Y00986*
X02721*
X0272Y00987*
X02714Y00991*
X02708Y00992*
X02702Y00991*
X02697Y00987*
X02692*
X02687Y00991*
X02681Y00992*
X02674Y00991*
X02669Y00987*
X02668Y00986*
X02662*
X02661Y00987*
X02655Y00991*
X02649Y00992*
X02643Y00991*
X02638Y00987*
X02633*
X02628Y00991*
X02622Y00992*
X02615Y00991*
X0261Y00987*
X02606Y00982*
X02605Y00976*
X02606Y0097*
X0261Y00964*
X02615Y00961*
X02622Y0096*
X02628Y00961*
X02633Y00964*
X02638*
X02643Y00961*
X02649Y0096*
X02655Y00961*
X02661Y00964*
X02662Y00966*
X02668*
X02669Y00964*
X02674Y00961*
X02681Y0096*
X02687Y00961*
X02692Y00964*
X02697*
X02702Y00961*
X02708Y0096*
X02714Y00961*
X0272Y00964*
X02721Y00966*
X02727*
X02728Y00964*
X02733Y00961*
X0274Y0096*
X02746Y00961*
X02751Y00964*
X02756*
X02761Y00961*
X02767Y0096*
X02773Y00961*
X02779Y00964*
X0278Y00966*
X02786*
X02787Y00964*
X02792Y00961*
X02799Y0096*
X02805Y00961*
X0281Y00964*
X02815*
X0282Y00961*
X02826Y0096*
X02833Y00961*
X02838Y00964*
X02841Y0097*
X02843Y00976*
X02841Y00982*
X02838Y00987*
X02833Y00991*
X02826Y00992*
G37*
G36*
X04366Y01045D02*
X04289D01*
Y00968*
X04366*
Y01045*
G37*
G36*
X05327Y01046D02*
X05317Y01045D01*
X05308Y01041*
X053Y01034*
X05294Y01026*
X0529Y01017*
X05288Y01007*
X0529Y00997*
X05294Y00988*
X053Y0098*
X05308Y00973*
X05317Y00969*
X05327Y00968*
X05337Y00969*
X05347Y00973*
X05355Y0098*
X05361Y00988*
X05365Y00997*
X05366Y01007*
X05365Y01017*
X05361Y01026*
X05355Y01034*
X05347Y01041*
X05337Y01045*
X05327Y01046*
G37*
G36*
X05127D02*
X05117Y01045D01*
X05108Y01041*
X051Y01034*
X05094Y01026*
X0509Y01017*
X05088Y01007*
X0509Y00997*
X05094Y00988*
X051Y0098*
X05108Y00973*
X05117Y00969*
X05127Y00968*
X05137Y00969*
X05147Y00973*
X05155Y0098*
X05161Y00988*
X05165Y00997*
X05166Y01007*
X05165Y01017*
X05161Y01026*
X05155Y01034*
X05147Y01041*
X05137Y01045*
X05127Y01046*
G37*
G36*
X04927D02*
X04917Y01045D01*
X04908Y01041*
X049Y01034*
X04894Y01026*
X0489Y01017*
X04888Y01007*
X0489Y00997*
X04894Y00988*
X049Y0098*
X04908Y00973*
X04917Y00969*
X04927Y00968*
X04937Y00969*
X04947Y00973*
X04955Y0098*
X04961Y00988*
X04965Y00997*
X04966Y01007*
X04965Y01017*
X04961Y01026*
X04955Y01034*
X04947Y01041*
X04937Y01045*
X04927Y01046*
G37*
G36*
X0299Y00977D02*
X02983Y00976D01*
X02976Y00972*
X02972Y00965*
X02971Y00958*
X02972Y00951*
X02976Y00945*
X02983Y0094*
X0299Y00939*
X02997Y0094*
X03004Y00945*
X03008Y00951*
X03009Y00958*
X03008Y00965*
X03004Y00972*
X02997Y00976*
X0299Y00977*
G37*
G36*
X02203D02*
X02195Y00976D01*
X02189Y00972*
X02185Y00965*
X02183Y00958*
X02185Y00951*
X02189Y00945*
X02195Y0094*
X02203Y00939*
X0221Y0094*
X02216Y00945*
X0222Y00951*
X02222Y00958*
X0222Y00965*
X02216Y00972*
X0221Y00976*
X02203Y00977*
G37*
G36*
X02478Y00953D02*
X02472Y00952D01*
X02467Y00948*
X02463Y00943*
X02462Y00937*
X02463Y0093*
X02467Y00925*
X02472Y00921*
X02478Y0092*
X02485Y00921*
X0249Y00925*
X02493Y0093*
X02495Y00937*
X02493Y00943*
X0249Y00948*
X02485Y00952*
X02478Y00953*
G37*
G36*
X01004Y00922D02*
X00998Y00921D01*
X00993Y00917*
X00989Y00912*
X00988Y00906*
X00989Y00899*
X00993Y00894*
X00998Y0089*
X01004Y00889*
X01011Y0089*
X01016Y00894*
X01019Y00899*
X01021Y00906*
X01019Y00912*
X01016Y00917*
X01011Y00921*
X01004Y00922*
G37*
G36*
X03617Y00983D02*
X03604Y00982D01*
X03592Y00978*
X0358Y00972*
X0357Y00963*
X03561Y00953*
X03555Y00942*
X03551Y00929*
X0355Y00916*
X03551Y00903*
X03555Y0089*
X03561Y00878*
X0357Y00868*
X0358Y0086*
X03592Y00854*
X03604Y0085*
X03617Y00848*
X03631Y0085*
X03643Y00854*
X03655Y0086*
X03665Y00868*
X03673Y00878*
X0368Y0089*
X03684Y00903*
X03685Y00916*
X03684Y00929*
X0368Y00942*
X03673Y00953*
X03665Y00963*
X03655Y00972*
X03643Y00978*
X03631Y00982*
X03617Y00983*
G37*
G36*
X01652D02*
X01639Y00982D01*
X01627Y00978*
X01615Y00972*
X01605Y00963*
X01596Y00953*
X0159Y00942*
X01586Y00929*
X01585Y00916*
X01586Y00903*
X0159Y0089*
X01596Y00878*
X01605Y00868*
X01615Y0086*
X01627Y00854*
X01639Y0085*
X01652Y00848*
X01666Y0085*
X01678Y00854*
X0169Y0086*
X017Y00868*
X01708Y00878*
X01715Y0089*
X01719Y00903*
X0172Y00916*
X01719Y00929*
X01715Y00942*
X01708Y00953*
X017Y00963*
X0169Y00972*
X01678Y00978*
X01666Y00982*
X01652Y00983*
G37*
G36*
X05578Y00936D02*
X05566Y00934D01*
X05555Y0093*
X05545Y00923*
X05538Y00913*
X05533Y00902*
X05532Y0089*
X05533Y00878*
X05538Y00867*
X05545Y00858*
X05555Y0085*
X05566Y00846*
X05578Y00844*
X0559Y00846*
X05601Y0085*
X0561Y00858*
X05617Y00867*
X05622Y00878*
X05624Y0089*
X05622Y00902*
X05617Y00913*
X0561Y00923*
X05601Y0093*
X0559Y00934*
X05578Y00936*
G37*
G36*
X03979D02*
X03967Y00934D01*
X03956Y0093*
X03947Y00923*
X03939Y00913*
X03935Y00902*
X03933Y0089*
X03935Y00878*
X03939Y00867*
X03947Y00858*
X03956Y0085*
X03967Y00846*
X03979Y00844*
X03991Y00846*
X04002Y0085*
X04012Y00858*
X04019Y00867*
X04024Y00878*
X04025Y0089*
X04024Y00902*
X04019Y00913*
X04012Y00923*
X04002Y0093*
X03991Y00934*
X03979Y00936*
G37*
G36*
X00199Y0097D02*
X00187Y00969D01*
X00175Y00965*
X00164Y00959*
X00154Y00951*
X00146Y00941*
X0014Y0093*
X00136Y00918*
X00135Y00906*
X00136Y00893*
X0014Y00881*
X00146Y0087*
X00154Y0086*
X00164Y00852*
X00175Y00846*
X00187Y00842*
X00199Y00841*
X00212Y00842*
X00224Y00846*
X00235Y00852*
X00245Y0086*
X00253Y0087*
X00259Y00881*
X00262Y00893*
X00264Y00906*
X00262Y00918*
X00259Y0093*
X00253Y00941*
X00245Y00951*
X00235Y00959*
X00224Y00965*
X00212Y00969*
X00199Y0097*
G37*
G36*
X02759Y00811D02*
X02753Y0081D01*
X02748Y00806*
X02743*
X02738Y0081*
X02732Y00811*
X02726Y0081*
X0272Y00806*
X02717Y00801*
X02715Y00795*
X02717Y00789*
X0272Y00783*
X02726Y0078*
X02732Y00778*
X02738Y0078*
X02743Y00783*
X02748*
X02753Y0078*
X02759Y00778*
X02766Y0078*
X02771Y00783*
X02774Y00789*
X02776Y00795*
X02774Y00801*
X02771Y00806*
X02766Y0081*
X02759Y00811*
G37*
G36*
X02692D02*
X02686Y0081D01*
X02681Y00806*
X02676*
X02671Y0081*
X02665Y00811*
X02659Y0081*
X02653Y00806*
X0265Y00801*
X02649Y00795*
X0265Y00789*
X02653Y00783*
X02659Y0078*
X02665Y00778*
X02671Y0078*
X02676Y00783*
X02681*
X02686Y0078*
X02692Y00778*
X02699Y0078*
X02704Y00783*
X02707Y00789*
X02709Y00795*
X02707Y00801*
X02704Y00806*
X02699Y0081*
X02692Y00811*
G37*
G36*
X02625D02*
X02619Y0081D01*
X02614Y00806*
X02609*
X02604Y0081*
X02598Y00811*
X02592Y0081*
X02586Y00806*
X02583Y00801*
X02582Y00795*
X02583Y00789*
X02586Y00783*
X02592Y0078*
X02598Y00778*
X02604Y0078*
X02609Y00783*
X02614*
X02619Y0078*
X02625Y00778*
X02632Y0078*
X02637Y00783*
X02641Y00789*
X02642Y00795*
X02641Y00801*
X02637Y00806*
X02632Y0081*
X02625Y00811*
G37*
G36*
X02893D02*
X02887Y0081D01*
X02882Y00806*
X0288Y00805*
X02874*
X02873Y00806*
X02868Y0081*
X02862Y00811*
X02855Y0081*
X0285Y00806*
X02847Y00801*
X02847Y00801*
X02841*
X02841Y00801*
X02838Y00806*
X02833Y0081*
X02826Y00811*
X0282Y0081*
X02815Y00806*
X0281*
X02805Y0081*
X02799Y00811*
X02792Y0081*
X02787Y00806*
X02784Y00801*
X02782Y00795*
X02784Y00789*
X02787Y00783*
X02792Y0078*
X02799Y00778*
X02805Y0078*
X0281Y00783*
X02815*
X0282Y0078*
X02826Y00778*
X02833Y0078*
X02838Y00783*
X02841Y00789*
X02841Y00789*
X02847*
X02847Y00789*
X0285Y00783*
X02855Y0078*
X02862Y00778*
X02868Y0078*
X02873Y00783*
X02874Y00785*
X0288*
X02882Y00783*
X02887Y0078*
X02893Y00778*
X02899Y0078*
X02905Y00783*
X02908Y00789*
X0291Y00795*
X02908Y00801*
X02905Y00806*
X02899Y0081*
X02893Y00811*
G37*
G36*
X0099Y00703D02*
X00983Y00702D01*
X00978Y00698*
X00975Y00693*
X00973Y00687*
X00975Y0068*
X00978Y00675*
X00983Y00671*
X0099Y0067*
X00996Y00671*
X01001Y00675*
X01005Y0068*
X01006Y00687*
X01005Y00693*
X01001Y00698*
X00996Y00702*
X0099Y00703*
G37*
G36*
X02469Y00427D02*
X02463Y00426D01*
X02458Y00422*
X02454Y00417*
X02453Y0041*
X02454Y00404*
X02458Y00399*
X02463Y00395*
X02469Y00394*
X02476Y00395*
X02481Y00399*
X02484Y00404*
X02486Y0041*
X02484Y00417*
X02481Y00422*
X02476Y00426*
X02469Y00427*
G37*
G36*
X0298Y00425D02*
X02974Y00424D01*
X02968Y0042*
X02965Y00415*
X02964Y00409*
X02965Y00402*
X02968Y00397*
X02974Y00394*
X0298Y00392*
X02986Y00394*
X02991Y00397*
X02995Y00402*
X02996Y00409*
X02995Y00415*
X02991Y0042*
X02986Y00424*
X0298Y00425*
G37*
G36*
X03019Y00421D02*
X03013Y0042D01*
X03008Y00417*
X03004Y00411*
X03003Y00405*
X03004Y00399*
X03008Y00393*
X03013Y0039*
X03019Y00389*
X03025Y0039*
X03031Y00393*
X03034Y00399*
X03036Y00405*
X03034Y00411*
X03031Y00417*
X03025Y0042*
X03019Y00421*
G37*
G36*
X02821Y00424D02*
X02815Y00422D01*
X0281Y00419*
X02806Y00414*
X02805Y00407*
X02806Y00401*
X0281Y00396*
X02815Y00392*
X02821Y00391*
X02828Y00392*
X02833Y00396*
X02834Y00397*
X02835Y00398*
X0284Y00397*
X02842Y00393*
X02848Y0039*
X02854Y00389*
X0286Y0039*
X02865Y00393*
X02869Y00399*
X0287Y00405*
X02869Y00411*
X02865Y00417*
X0286Y0042*
X02854Y00421*
X02848Y0042*
X02842Y00417*
X02841Y00415*
X02841Y00415*
X02835Y00415*
X02833Y00419*
X02828Y00422*
X02821Y00424*
G37*
G36*
X02704Y00421D02*
X02698Y0042D01*
X02693Y00417*
X02689Y00411*
X02688Y00405*
X02689Y00399*
X02693Y00393*
X02698Y0039*
X02704Y00389*
X0271Y0039*
X02716Y00393*
X02719Y00399*
X02721Y00405*
X02719Y00411*
X02716Y00417*
X0271Y0042*
X02704Y00421*
G37*
G36*
X02665D02*
X02659Y0042D01*
X02653Y00417*
X0265Y00411*
X02649Y00405*
X0265Y00399*
X02653Y00393*
X02659Y0039*
X02665Y00389*
X02671Y0039*
X02676Y00393*
X0268Y00399*
X02681Y00405*
X0268Y00411*
X02676Y00417*
X02671Y0042*
X02665Y00421*
G37*
G36*
X02511D02*
X02505Y0042D01*
X025Y00417*
X02496Y00411*
X02495Y00405*
X02496Y00399*
X025Y00393*
X02505Y0039*
X02511Y00389*
X02518Y0039*
X02523Y00393*
X02526Y00399*
X02528Y00405*
X02526Y00411*
X02523Y00417*
X02518Y0042*
X02511Y00421*
G37*
G36*
X02389D02*
X02383Y0042D01*
X02378Y00417*
X02374Y00411*
X02373Y00405*
X02374Y00399*
X02378Y00393*
X02383Y0039*
X02389Y00389*
X02396Y0039*
X02401Y00393*
X02404Y00399*
X02406Y00405*
X02404Y00411*
X02401Y00417*
X02396Y0042*
X02389Y00421*
G37*
G36*
X0235D02*
X02344Y0042D01*
X02338Y00417*
X02335Y00411*
X02334Y00405*
X02335Y00399*
X02338Y00393*
X02344Y0039*
X0235Y00389*
X02356Y0039*
X02361Y00393*
X02365Y00399*
X02366Y00405*
X02365Y00411*
X02361Y00417*
X02356Y0042*
X0235Y00421*
G37*
G36*
X01872Y00303D02*
X01865Y00302D01*
X01862Y003*
X01858Y00302*
X01852Y00303*
X01846Y00302*
X01842Y003*
X01838Y00302*
X01832Y00303*
X01826Y00302*
X01821Y00298*
X01817Y00293*
X01816Y00287*
X01817Y00281*
X01821Y00275*
X01822Y00274*
Y00268*
X01821Y00267*
X01817Y00262*
X01816Y00255*
X01817Y00249*
X01821Y00244*
X01826Y0024*
X01832Y00239*
X01838Y0024*
X01842Y00243*
X01846Y0024*
X01852Y00239*
X01858Y0024*
X01862Y00243*
X01865Y0024*
X01872Y00239*
X01878Y0024*
X01883Y00244*
X01887Y00249*
X01888Y00255*
X01887Y00262*
X01883Y00267*
X01881Y00268*
Y00274*
X01883Y00275*
X01887Y00281*
X01888Y00287*
X01887Y00293*
X01883Y00298*
X01878Y00302*
X01872Y00303*
G37*
G36*
X02112D02*
X02105Y00302D01*
X021Y00298*
X02097Y00293*
X02097Y00293*
X02091*
X02091Y00293*
X02088Y00298*
X02083Y00302*
X02076Y00303*
X0207Y00302*
X02065Y00298*
X02061Y00293*
X0206Y00287*
X02061Y00281*
X02065Y00275*
X02067Y00274*
Y00268*
X02065Y00267*
X02061Y00262*
X0206Y00255*
X02061Y00249*
X02065Y00244*
X0207Y0024*
X02076Y00239*
X02083Y0024*
X02088Y00244*
X02091Y00249*
X02091Y0025*
X02097*
X02097Y00249*
X021Y00244*
X02105Y0024*
X02112Y00239*
X02118Y0024*
X02123Y00244*
X02127Y00249*
X02128Y00255*
X02127Y00262*
X02123Y00267*
X02121Y00268*
Y00274*
X02123Y00275*
X02127Y00281*
X02128Y00287*
X02127Y00293*
X02123Y00298*
X02118Y00302*
X02112Y00303*
G37*
G36*
X0261Y00295D02*
X02603Y00294D01*
X02598Y00291*
X02597Y00289*
X02591*
X0259Y00291*
X02584Y00294*
X02578Y00295*
X02572Y00294*
X02567Y00291*
X02563Y00285*
X02562Y00279*
X02563Y00273*
X02567Y00267*
X02572Y00264*
X02578Y00263*
X02584Y00264*
X0259Y00267*
X02591Y00269*
X02597*
X02598Y00267*
X02603Y00264*
X0261Y00263*
X02616Y00264*
X02621Y00267*
X02625Y00273*
X02626Y00279*
X02625Y00285*
X02621Y00291*
X02616Y00294*
X0261Y00295*
G37*
G36*
X02444D02*
X02438Y00294D01*
X02433Y00291*
X02432Y00289*
X02426*
X02424Y00291*
X02419Y00294*
X02413Y00295*
X02407Y00294*
X02401Y00291*
X02398Y00285*
X02397Y00279*
X02398Y00273*
X02401Y00267*
X02407Y00264*
X02413Y00263*
X02419Y00264*
X02424Y00267*
X02426Y00269*
X02432*
X02433Y00267*
X02438Y00264*
X02444Y00263*
X02451Y00264*
X02456Y00267*
X02459Y00273*
X02461Y00279*
X02459Y00285*
X02456Y00291*
X02451Y00294*
X02444Y00295*
G37*
G36*
X02937D02*
X0293Y00294D01*
X02925Y00291*
X02924Y00289*
X02918*
X02917Y00291*
X02911Y00294*
X02905Y00295*
X02899Y00294*
X02893Y00291*
X0289Y00285*
X02889Y00279*
X0289Y00273*
X02893Y00267*
X02899Y00264*
X02905Y00263*
X02911Y00264*
X02917Y00267*
X02918Y00269*
X02924*
X02925Y00267*
X0293Y00264*
X02937Y00263*
X02943Y00264*
X02948Y00267*
X02952Y00273*
X02953Y00279*
X02952Y00285*
X02948Y00291*
X02943Y00294*
X02937Y00295*
G37*
G36*
X02748Y00298D02*
X02742Y00297D01*
X02737Y00293*
X02733Y00288*
X02732Y00282*
X02733Y00276*
X02737Y0027*
X02742Y00267*
X02748Y00266*
X02755Y00267*
X0276Y0027*
X02766Y0027*
X02767Y00267*
X02773Y00264*
X02779Y00263*
X02785Y00264*
X02791Y00267*
X02794Y00273*
X02795Y00279*
X02794Y00285*
X02791Y00291*
X02785Y00294*
X02779Y00295*
X02773Y00294*
X02767Y00291*
X02762Y00291*
X0276Y00293*
X02755Y00297*
X02748Y00298*
G37*
G36*
X02151Y00303D02*
X02145Y00302D01*
X0214Y00298*
X02136Y00293*
X02135Y00287*
X02136Y00281*
X0214Y00275*
X02141Y00274*
Y00268*
X0214Y00267*
X02136Y00262*
X02135Y00255*
X02136Y00249*
X0214Y00244*
X02145Y0024*
X02151Y00239*
X02157Y0024*
X02163Y00244*
X02166Y00249*
X02167Y00255*
X02166Y00262*
X02163Y00267*
X02161Y00268*
Y00274*
X02163Y00275*
X02166Y00281*
X02167Y00287*
X02166Y00293*
X02163Y00298*
X02157Y00302*
X02151Y00303*
G37*
G36*
X00285Y00501D02*
X00264Y00499D01*
X00244Y00494*
X00224Y00486*
X00207Y00476*
X00191Y00462*
X00177Y00446*
X00166Y00428*
X00158Y00409*
X00153Y00388*
X00152Y00368*
X00153Y00347*
X00158Y00326*
X00166Y00307*
X00177Y00289*
X00191Y00273*
X00207Y0026*
X00224Y00249*
X00244Y00241*
X00264Y00236*
X00285Y00234*
X00306Y00236*
X00326Y00241*
X00346Y00249*
X00363Y0026*
X00379Y00273*
X00393Y00289*
X00404Y00307*
X00412Y00326*
X00417Y00347*
X00418Y00368*
X00417Y00388*
X00412Y00409*
X00404Y00428*
X00393Y00446*
X00379Y00462*
X00363Y00476*
X00346Y00486*
X00326Y00494*
X00306Y00499*
X00285Y00501*
G37*
%LNgrandmaster-3*%
%LPD*%
G54D143*
X00299Y01006D03*
Y00806D03*
X00099D03*
Y01006D03*
X00299Y02581D03*
Y02381D03*
X00099D03*
Y02581D03*
X00299Y02056D03*
Y01856D03*
X00099D03*
Y02056D03*
X00299Y01531D03*
Y01331D03*
X00099D03*
Y01531D03*
G54D158*
X05127Y02307D03*
G54D160*
X05578Y01689D03*
X03979Y02489D03*
G54D161*
X069Y03589D03*
X06734D03*
X06569D03*
G54D162*
X05934Y03937D03*
G54D163*
X06119Y04056D03*
G54D171*
X04039Y03784D03*
X02878Y00249D03*
X02957Y00251D03*
X02447Y00242D03*
X02606Y00931D03*
X02636Y00247D03*
X02799Y00251D03*
X02409Y01088D03*
X02311Y0109D03*
X02508Y00931D03*
X02409Y00932D03*
X02724Y01093D03*
X02784Y01094D03*
X02842Y01095D03*
X02546Y00244D03*
X03097Y00251D03*
X02606Y01091D03*
X03554Y01841D03*
X03719Y01996D03*
X01721Y0189D03*
X01671Y01792D03*
X01674Y01989D03*
X02508Y0109D03*
X03413Y01573D03*
X0167Y01595D03*
X02409Y02579D03*
X02586Y02569D03*
X01718Y01792D03*
X02881Y02566D03*
X03732Y01418D03*
X02253Y02279D03*
X02311Y00934D03*
X03554Y01991D03*
X01675Y01891D03*
X02783Y02429D03*
X03719Y01921D03*
X02665Y01092D03*
X02475Y02456D03*
X03414Y01805D03*
X02685Y02311D03*
X0359Y01662D03*
X02404Y02412D03*
X01716Y01399D03*
X01721Y01989D03*
X03549Y01413D03*
X02488Y02413D03*
X0167Y01694D03*
X02901Y01095D03*
X03594Y01514D03*
X03406Y01461D03*
X0341Y01713D03*
X02933Y00953D03*
X02871Y02297D03*
X02685Y02568D03*
X03554Y01941D03*
X02783Y02568D03*
X03718Y01713D03*
X01721Y01694D03*
X01671Y01399D03*
X02581Y02308D03*
X01718Y01497D03*
X01714Y01595D03*
X01671Y01497D03*
X02321Y02586D03*
X02034Y00246D03*
X01916Y00244D03*
X02309Y00246D03*
X0333Y03301D03*
X0412Y03594D03*
X03183Y03135D03*
X03277Y02963D03*
X02419Y02788D03*
X02413Y03295D03*
X02321Y03361D03*
X02631Y02876D03*
X02473Y0298D03*
X00937Y02317D03*
X01726Y04329D03*
X01788D03*
X04477Y03135D03*
X04064Y02722D03*
X06628Y01372D03*
X06974Y01939D03*
X03968Y01671D03*
X04131Y01686D03*
X03996Y01711D03*
X0396Y02724D03*
X06253Y02909D03*
X06647Y03129D03*
X04339Y02725D03*
X0383Y03762D03*
X03395Y04222D03*
X04272Y03135D03*
X02139Y03738D03*
X04208Y03135D03*
X06626Y03032D03*
X04152Y03135D03*
X02724Y03521D03*
X01248Y02D03*
X04068Y03135D03*
X02674Y03501D03*
X04234Y02725D03*
X06456Y03009D03*
X01691Y04079D03*
X03642Y00636D03*
X06476Y03231D03*
X04333Y03135D03*
X01261Y02482D03*
X04114Y03135D03*
X06648Y03341D03*
X02888Y04221D03*
X0337Y02888D03*
X02258Y03741D03*
X01749Y0411D03*
X0229Y04217D03*
X0388Y03109D03*
X03744Y03342D03*
X03717Y03072D03*
X05733Y03556D03*
X05676Y03546D03*
X03603Y00682D03*
X06548Y01531D03*
X06602Y01612D03*
Y01672D03*
Y01722D03*
X06601Y01777D03*
X06685Y01828D03*
X06699Y01881D03*
X06949Y02095D03*
X06607Y02176D03*
X06395Y02111D03*
X06048Y02171D03*
X06004Y02434D03*
X06274Y02391D03*
X06398Y02453D03*
X06397Y02501D03*
X06396Y02556D03*
X06397Y0261D03*
X06398Y02657D03*
X06372Y02909D03*
X0491Y04203D03*
X04387Y04206D03*
X03777Y04023D03*
X04085Y03892D03*
X04194Y03884D03*
X04431Y03135D03*
X0286Y03787D03*
X02724Y03729D03*
X03531Y0366D03*
X03269Y03788D03*
X01242Y01472D03*
X01256Y00942D03*
X00654Y0079D03*
X00655Y01028D03*
X00654Y01314D03*
X00653Y01551D03*
X00654Y01839D03*
Y02073D03*
Y02365D03*
X00653Y02593D03*
G54D172*
X02531Y03853D03*
Y0283D03*
X00149D03*
Y03853D03*
M02*